FILE_TYPE = MACRO_DRAWING;
SET COLOR_WIRE YELLOW;
SET COLOR_PROP MONO;
SET COLOR_DOT WHITE;
SET COLOR_ARC YELLOW;
SET COLOR_BODY GREEN;
SET COLOR_NOTE MONO;
SET PROP_DISPLAY VALUE;
SET PAGE_NUMBER P232;
FORCEADD CAP..1
(-8550 875);
FORCEPROP 1 LASTPIN (-8550 775) $PN 2
J 0
(-8540 755);
DISPLAY 0.617021 (-8540 755);
PAINT GREEN (-8540 755);
FORCEPROP 1 LASTPIN (-8550 975) $PN 1
J 0
(-8540 955);
DISPLAY 0.617021 (-8540 955);
PAINT GREEN (-8540 955);
FORCEPROP 1 LAST MATERIAL X6S
J 0
(-8500 775);
DISPLAY 0.617021 (-8500 775);
PAINT SKYBLUE (-8500 775);
FORCEPROP 1 LAST PACK_TYPE 0603LF
J 0
(-8500 675);
DISPLAY 0.617021 (-8500 675);
PAINT SKYBLUE (-8500 675);
FORCEPROP 1 LAST TOLERANCE 20%
J 0
(-8500 825);
DISPLAY 0.617021 (-8500 825);
PAINT SKYBLUE (-8500 825);
FORCEPROP 1 LAST VALUE 10UF
J 0
(-8500 925);
DISPLAY 0.617021 (-8500 925);
PAINT SKYBLUE (-8500 925);
FORCEPROP 1 LAST PART_NUMBER E15431-001
J 0
(-8500 725);
DISPLAY 0.617021 (-8500 725);
PAINT BLUE (-8500 725);
FORCEPROP 1 LAST LOCATION C4L2
J 0
(-8500 975);
DISPLAY 0.617021 (-8500 975);
PAINT AQUA (-8500 975);
FORCEPROP 1 LAST VOLTAGE 4V
J 0
(-8500 875);
PAINT SKYBLUE (-8500 875);
DISPLAY INVISIBLE (-8500 875);
FORCEPROP 2 LAST CDS_LIB mstr_discrete
J 0
(-8550 875);
PAINT ORANGE (-8550 875);
DISPLAY INVISIBLE (-8550 875);
FORCEPROP 2 LAST CDS_LOCATION C4L2
J 0
(-8500 975);
DISPLAY 0.617021 (-8500 975);
PAINT AQUA (-8500 975);
DISPLAY INVISIBLE (-8500 975);
FORCEPROP 2 LAST ROOM PVPP_KLM_VR
J 0
(-8500 1025);
PAINT MONO (-8500 1025);
DISPLAY INVISIBLE (-8500 1025);
FORCEPROP 1 LAST PATH I102
J 0
(-8500 1025);
DISPLAY 0.978723 (-8500 1025);
PAINT WHITE (-8500 1025);
DISPLAY INVISIBLE (-8500 1025);
FORCEPROP 2 LAST $SEC 1
J 0
(-8500 1075);
PAINT MONO (-8500 1075);
DISPLAY INVISIBLE (-8500 1075);
FORCEPROP 2 LAST CDS_SEC 1
J 0
(-8500 1075);
PAINT MONO (-8500 1075);
DISPLAY INVISIBLE (-8500 1075);
FORCEPROP 2 LAST BOM_COST MEM_VRD_PVPP_AB
J 0
(-8500 1025);
PAINT MONO (-8500 1025);
DISPLAY INVISIBLE (-8500 1025);
FORCEADD PVPP_DEF..1
(-8550 1150);
FORCEPROP 3 LASTPIN (-8550 1100) SIG_NAME PVPP_DEF\g
J 0
(-8540 1110);
DISPLAY 0.659574 (-8540 1110);
PAINT MONO (-8540 1110);
DISPLAY INVISIBLE (-8540 1110);
FORCEPROP 1 LAST VOLTAGE 2.5V
J 0
(-8595 1107);
DISPLAY 0.340426 (-8595 1107);
PAINT SKYBLUE (-8595 1107);
DISPLAY INVISIBLE (-8595 1107);
FORCEPROP 1 LAST BODY_TYPE PLUMBING
J 0
(-8595 1107);
DISPLAY 0.340426 (-8595 1107);
PAINT GREEN (-8595 1107);
DISPLAY INVISIBLE (-8595 1107);
FORCEPROP 2 LAST CDS_LIB mstr_symbols
J 0
(-8550 1150);
PAINT ORANGE (-8550 1150);
DISPLAY INVISIBLE (-8550 1150);
FORCEPROP 1 LAST PATH I103
J 0
(-8500 1175);
DISPLAY 0.872340 (-8500 1175);
PAINT AQUA (-8500 1175);
DISPLAY INVISIBLE (-8500 1175);
FORCEPROP 1 LAST HDL_POWER PVPP_DEF
J 1
(-8550 1200);
DISPLAY 0.872340 (-8550 1200);
PAINT GREEN (-8550 1200);
DISPLAY INVISIBLE (-8550 1200);
FORCEPROP 2 LAST BOM_COST MEM_VRD_PVPP_AB
J 0
(-8475 1250);
PAINT MONO (-8475 1250);
DISPLAY INVISIBLE (-8475 1250);
FORCEPROP 2 LAST ROOM PVPP_KLM_VR
J 0
(-8300 1250);
PAINT ORANGE (-8300 1250);
DISPLAY INVISIBLE (-8300 1250);
FORCEADD CAP..1
(-8300 875);
FORCEPROP 1 LASTPIN (-8300 775) $PN 2
J 0
(-8290 755);
DISPLAY 0.617021 (-8290 755);
PAINT GREEN (-8290 755);
FORCEPROP 1 LASTPIN (-8300 975) $PN 1
J 0
(-8290 955);
DISPLAY 0.617021 (-8290 955);
PAINT GREEN (-8290 955);
FORCEPROP 1 LAST MATERIAL X6S
J 0
(-8250 775);
DISPLAY 0.617021 (-8250 775);
PAINT SKYBLUE (-8250 775);
FORCEPROP 1 LAST PACK_TYPE 0603LF
J 0
(-8250 675);
DISPLAY 0.617021 (-8250 675);
PAINT SKYBLUE (-8250 675);
FORCEPROP 1 LAST TOLERANCE 20%
J 0
(-8250 825);
DISPLAY 0.617021 (-8250 825);
PAINT SKYBLUE (-8250 825);
FORCEPROP 1 LAST VALUE 10UF
J 0
(-8250 925);
DISPLAY 0.617021 (-8250 925);
PAINT SKYBLUE (-8250 925);
FORCEPROP 1 LAST PART_NUMBER E15431-001
J 0
(-8250 725);
DISPLAY 0.617021 (-8250 725);
PAINT BLUE (-8250 725);
FORCEPROP 1 LAST LOCATION C6A3
J 0
(-8250 975);
DISPLAY 0.617021 (-8250 975);
PAINT AQUA (-8250 975);
FORCEPROP 1 LAST VOLTAGE 4V
J 0
(-8250 875);
PAINT SKYBLUE (-8250 875);
DISPLAY INVISIBLE (-8250 875);
FORCEPROP 2 LAST CDS_LIB mstr_discrete
J 0
(-8300 875);
PAINT ORANGE (-8300 875);
DISPLAY INVISIBLE (-8300 875);
FORCEPROP 2 LAST CDS_LOCATION C6A3
J 0
(-8250 975);
DISPLAY 0.617021 (-8250 975);
PAINT AQUA (-8250 975);
DISPLAY INVISIBLE (-8250 975);
FORCEPROP 2 LAST BOM_COST MEM_VRD_PVPP_AB
J 0
(-8250 1025);
PAINT MONO (-8250 1025);
DISPLAY INVISIBLE (-8250 1025);
FORCEPROP 2 LAST CDS_SEC 1
J 0
(-8250 1075);
PAINT MONO (-8250 1075);
DISPLAY INVISIBLE (-8250 1075);
FORCEPROP 2 LAST $SEC 1
J 0
(-8250 1075);
PAINT MONO (-8250 1075);
DISPLAY INVISIBLE (-8250 1075);
FORCEPROP 1 LAST PATH I104
J 0
(-8250 1025);
DISPLAY 0.978723 (-8250 1025);
PAINT WHITE (-8250 1025);
DISPLAY INVISIBLE (-8250 1025);
FORCEPROP 2 LAST ROOM PVPP_KLM_VR
J 0
(-8250 1025);
PAINT MONO (-8250 1025);
DISPLAY INVISIBLE (-8250 1025);
FORCEADD CAP..1
(-8025 875);
FORCEPROP 1 LASTPIN (-8025 775) $PN 2
J 0
(-8015 755);
DISPLAY 0.617021 (-8015 755);
PAINT GREEN (-8015 755);
FORCEPROP 1 LASTPIN (-8025 975) $PN 1
J 0
(-8015 955);
DISPLAY 0.617021 (-8015 955);
PAINT GREEN (-8015 955);
FORCEPROP 1 LAST MATERIAL X6S
J 0
(-7975 775);
DISPLAY 0.617021 (-7975 775);
PAINT SKYBLUE (-7975 775);
FORCEPROP 1 LAST PACK_TYPE 0603LF
J 0
(-7975 675);
DISPLAY 0.617021 (-7975 675);
PAINT SKYBLUE (-7975 675);
FORCEPROP 1 LAST TOLERANCE 20%
J 0
(-7975 825);
DISPLAY 0.617021 (-7975 825);
PAINT SKYBLUE (-7975 825);
FORCEPROP 1 LAST VALUE 10UF
J 0
(-7975 925);
DISPLAY 0.617021 (-7975 925);
PAINT SKYBLUE (-7975 925);
FORCEPROP 1 LAST PART_NUMBER E15431-001
J 0
(-7975 725);
DISPLAY 0.617021 (-7975 725);
PAINT BLUE (-7975 725);
FORCEPROP 1 LAST LOCATION C6A2
J 0
(-7975 975);
DISPLAY 0.617021 (-7975 975);
PAINT AQUA (-7975 975);
FORCEPROP 1 LAST VOLTAGE 4V
J 0
(-7975 875);
PAINT SKYBLUE (-7975 875);
DISPLAY INVISIBLE (-7975 875);
FORCEPROP 2 LAST CDS_LIB mstr_discrete
J 0
(-8025 875);
PAINT ORANGE (-8025 875);
DISPLAY INVISIBLE (-8025 875);
FORCEPROP 2 LAST CDS_LOCATION C6A2
J 0
(-7975 975);
DISPLAY 0.617021 (-7975 975);
PAINT AQUA (-7975 975);
DISPLAY INVISIBLE (-7975 975);
FORCEPROP 2 LAST BOM_COST MEM_VRD_PVPP_AB
J 0
(-7975 1025);
PAINT MONO (-7975 1025);
DISPLAY INVISIBLE (-7975 1025);
FORCEPROP 2 LAST CDS_SEC 1
J 0
(-7975 1075);
PAINT MONO (-7975 1075);
DISPLAY INVISIBLE (-7975 1075);
FORCEPROP 2 LAST $SEC 1
J 0
(-7975 1075);
PAINT MONO (-7975 1075);
DISPLAY INVISIBLE (-7975 1075);
FORCEPROP 1 LAST PATH I105
J 0
(-7975 1025);
DISPLAY 0.978723 (-7975 1025);
PAINT WHITE (-7975 1025);
DISPLAY INVISIBLE (-7975 1025);
FORCEPROP 2 LAST ROOM PVPP_KLM_VR
J 0
(-7975 1025);
PAINT MONO (-7975 1025);
DISPLAY INVISIBLE (-7975 1025);
FORCEADD CAP..1
(-7775 850);
FORCEPROP 1 LASTPIN (-7775 750) $PN 2
J 0
(-7765 730);
DISPLAY 0.617021 (-7765 730);
PAINT GREEN (-7765 730);
FORCEPROP 1 LASTPIN (-7775 950) $PN 1
J 0
(-7765 930);
DISPLAY 0.617021 (-7765 930);
PAINT GREEN (-7765 930);
FORCEPROP 1 LAST MATERIAL X6S
J 0
(-7725 750);
DISPLAY 0.617021 (-7725 750);
PAINT SKYBLUE (-7725 750);
FORCEPROP 1 LAST PACK_TYPE 0603LF
J 0
(-7725 650);
DISPLAY 0.617021 (-7725 650);
PAINT SKYBLUE (-7725 650);
FORCEPROP 1 LAST TOLERANCE 20%
J 0
(-7725 800);
DISPLAY 0.617021 (-7725 800);
PAINT SKYBLUE (-7725 800);
FORCEPROP 1 LAST VALUE 10UF
J 0
(-7725 900);
DISPLAY 0.617021 (-7725 900);
PAINT SKYBLUE (-7725 900);
FORCEPROP 1 LAST PART_NUMBER E15431-001
J 0
(-7725 700);
DISPLAY 0.617021 (-7725 700);
PAINT BLUE (-7725 700);
FORCEPROP 1 LAST LOCATION C4L3
J 0
(-7725 950);
DISPLAY 0.617021 (-7725 950);
PAINT AQUA (-7725 950);
FORCEPROP 1 LAST VOLTAGE 4V
J 0
(-7725 850);
PAINT SKYBLUE (-7725 850);
DISPLAY INVISIBLE (-7725 850);
FORCEPROP 2 LAST CDS_LIB mstr_discrete
J 0
(-7775 850);
PAINT ORANGE (-7775 850);
DISPLAY INVISIBLE (-7775 850);
FORCEPROP 2 LAST CDS_LOCATION C4L3
J 0
(-7725 950);
DISPLAY 0.617021 (-7725 950);
PAINT AQUA (-7725 950);
DISPLAY INVISIBLE (-7725 950);
FORCEPROP 2 LAST ROOM PVPP_KLM_VR
J 0
(-7725 1000);
PAINT MONO (-7725 1000);
DISPLAY INVISIBLE (-7725 1000);
FORCEPROP 1 LAST PATH I106
J 0
(-7725 1000);
DISPLAY 0.978723 (-7725 1000);
PAINT WHITE (-7725 1000);
DISPLAY INVISIBLE (-7725 1000);
FORCEPROP 2 LAST BOM_COST MEM_VRD_PVPP_AB
J 0
(-7725 1000);
PAINT MONO (-7725 1000);
DISPLAY INVISIBLE (-7725 1000);
FORCEPROP 2 LAST CDS_SEC 1
J 0
(-7725 1050);
PAINT MONO (-7725 1050);
DISPLAY INVISIBLE (-7725 1050);
FORCEPROP 2 LAST $SEC 1
J 0
(-7725 1050);
PAINT MONO (-7725 1050);
DISPLAY INVISIBLE (-7725 1050);
FORCEADD CAP..1
(-7500 875);
FORCEPROP 1 LASTPIN (-7500 775) $PN 2
J 0
(-7490 755);
DISPLAY 0.617021 (-7490 755);
PAINT GREEN (-7490 755);
FORCEPROP 1 LASTPIN (-7500 975) $PN 1
J 0
(-7490 955);
DISPLAY 0.617021 (-7490 955);
PAINT GREEN (-7490 955);
FORCEPROP 1 LAST MATERIAL X6S
J 0
(-7450 775);
DISPLAY 0.617021 (-7450 775);
PAINT SKYBLUE (-7450 775);
FORCEPROP 1 LAST PACK_TYPE 0603LF
J 0
(-7450 675);
DISPLAY 0.617021 (-7450 675);
PAINT SKYBLUE (-7450 675);
FORCEPROP 1 LAST TOLERANCE 20%
J 0
(-7450 825);
DISPLAY 0.617021 (-7450 825);
PAINT SKYBLUE (-7450 825);
FORCEPROP 1 LAST VALUE 10UF
J 0
(-7450 925);
DISPLAY 0.617021 (-7450 925);
PAINT SKYBLUE (-7450 925);
FORCEPROP 1 LAST LOCATION C4L4
J 0
(-7450 975);
DISPLAY 0.617021 (-7450 975);
PAINT AQUA (-7450 975);
FORCEPROP 1 LAST PART_NUMBER E15431-001
J 0
(-7450 725);
DISPLAY 0.617021 (-7450 725);
PAINT BLUE (-7450 725);
FORCEPROP 1 LAST VOLTAGE 4V
J 0
(-7450 875);
PAINT SKYBLUE (-7450 875);
DISPLAY INVISIBLE (-7450 875);
FORCEPROP 2 LAST CDS_LIB mstr_discrete
J 0
(-7500 875);
PAINT ORANGE (-7500 875);
DISPLAY INVISIBLE (-7500 875);
FORCEPROP 2 LAST CDS_LOCATION C4L4
J 0
(-7450 975);
DISPLAY 0.617021 (-7450 975);
PAINT AQUA (-7450 975);
DISPLAY INVISIBLE (-7450 975);
FORCEPROP 2 LAST BOM_COST MEM_VRD_PVPP_AB
J 0
(-7450 1025);
PAINT MONO (-7450 1025);
DISPLAY INVISIBLE (-7450 1025);
FORCEPROP 2 LAST CDS_SEC 1
J 0
(-7450 1075);
PAINT MONO (-7450 1075);
DISPLAY INVISIBLE (-7450 1075);
FORCEPROP 2 LAST $SEC 1
J 0
(-7450 1075);
PAINT MONO (-7450 1075);
DISPLAY INVISIBLE (-7450 1075);
FORCEPROP 1 LAST PATH I108
J 0
(-7450 1025);
DISPLAY 0.978723 (-7450 1025);
PAINT WHITE (-7450 1025);
DISPLAY INVISIBLE (-7450 1025);
FORCEPROP 2 LAST ROOM PVPP_KLM_VR
J 0
(-7450 1025);
PAINT MONO (-7450 1025);
DISPLAY INVISIBLE (-7450 1025);
FORCEADD CAP..1
(-7200 875);
FORCEPROP 1 LASTPIN (-7200 975) $PN 1
J 0
(-7190 955);
DISPLAY 0.617021 (-7190 955);
PAINT GREEN (-7190 955);
FORCEPROP 1 LASTPIN (-7200 775) $PN 2
J 0
(-7190 755);
DISPLAY 0.617021 (-7190 755);
PAINT GREEN (-7190 755);
FORCEPROP 1 LAST PACK_TYPE 0603LF
J 0
(-7150 675);
DISPLAY 0.617021 (-7150 675);
PAINT SKYBLUE (-7150 675);
FORCEPROP 1 LAST LOCATION C6A7
J 0
(-7150 975);
DISPLAY 0.617021 (-7150 975);
PAINT AQUA (-7150 975);
FORCEPROP 1 LAST VALUE 10UF
J 0
(-7150 925);
DISPLAY 0.617021 (-7150 925);
PAINT SKYBLUE (-7150 925);
FORCEPROP 1 LAST TOLERANCE 20%
J 0
(-7150 825);
DISPLAY 0.617021 (-7150 825);
PAINT SKYBLUE (-7150 825);
FORCEPROP 1 LAST MATERIAL X6S
J 0
(-7150 775);
DISPLAY 0.617021 (-7150 775);
PAINT SKYBLUE (-7150 775);
FORCEPROP 1 LAST PART_NUMBER E15431-001
J 0
(-7150 725);
DISPLAY 0.617021 (-7150 725);
PAINT BLUE (-7150 725);
FORCEPROP 2 LAST CDS_LIB mstr_discrete
J 0
(-7200 875);
PAINT ORANGE (-7200 875);
DISPLAY INVISIBLE (-7200 875);
FORCEPROP 1 LAST VOLTAGE 4V
J 0
(-7150 875);
PAINT SKYBLUE (-7150 875);
DISPLAY INVISIBLE (-7150 875);
FORCEPROP 2 LAST CDS_LOCATION C6A7
J 0
(-7150 975);
DISPLAY 0.617021 (-7150 975);
PAINT AQUA (-7150 975);
DISPLAY INVISIBLE (-7150 975);
FORCEPROP 2 LAST ROOM PVPP_KLM_VR
J 0
(-7150 1025);
PAINT MONO (-7150 1025);
DISPLAY INVISIBLE (-7150 1025);
FORCEPROP 1 LAST PATH I109
J 0
(-7150 1025);
DISPLAY 0.978723 (-7150 1025);
PAINT WHITE (-7150 1025);
DISPLAY INVISIBLE (-7150 1025);
FORCEPROP 2 LAST $SEC 1
J 0
(-7150 1075);
PAINT MONO (-7150 1075);
DISPLAY INVISIBLE (-7150 1075);
FORCEPROP 2 LAST CDS_SEC 1
J 0
(-7150 1075);
PAINT MONO (-7150 1075);
DISPLAY INVISIBLE (-7150 1075);
FORCEPROP 2 LAST BOM_COST MEM_VRD_PVPP_AB
J 0
(-7150 1025);
PAINT MONO (-7150 1025);
DISPLAY INVISIBLE (-7150 1025);
FORCEADD CAP..1
(-6925 875);
FORCEPROP 1 LASTPIN (-6925 975) $PN 1
J 0
(-6915 955);
DISPLAY 0.617021 (-6915 955);
PAINT GREEN (-6915 955);
FORCEPROP 1 LASTPIN (-6925 775) $PN 2
J 0
(-6915 755);
DISPLAY 0.617021 (-6915 755);
PAINT GREEN (-6915 755);
FORCEPROP 1 LAST MATERIAL X6S
J 0
(-6875 775);
DISPLAY 0.617021 (-6875 775);
PAINT SKYBLUE (-6875 775);
FORCEPROP 1 LAST PACK_TYPE 0603LF
J 0
(-6875 675);
DISPLAY 0.617021 (-6875 675);
PAINT SKYBLUE (-6875 675);
FORCEPROP 1 LAST TOLERANCE 20%
J 0
(-6875 825);
DISPLAY 0.617021 (-6875 825);
PAINT SKYBLUE (-6875 825);
FORCEPROP 1 LAST VALUE 10UF
J 0
(-6875 925);
DISPLAY 0.617021 (-6875 925);
PAINT SKYBLUE (-6875 925);
FORCEPROP 1 LAST LOCATION C6A6
J 0
(-6875 975);
DISPLAY 0.617021 (-6875 975);
PAINT AQUA (-6875 975);
FORCEPROP 1 LAST PART_NUMBER E15431-001
J 0
(-6875 725);
DISPLAY 0.617021 (-6875 725);
PAINT BLUE (-6875 725);
FORCEPROP 2 LAST CDS_LIB mstr_discrete
J 0
(-6925 875);
PAINT MONO (-6925 875);
DISPLAY INVISIBLE (-6925 875);
FORCEPROP 2 LAST CDS_LOCATION C6A6
J 0
(-6875 975);
DISPLAY 0.617021 (-6875 975);
PAINT AQUA (-6875 975);
DISPLAY INVISIBLE (-6875 975);
FORCEPROP 1 LAST VOLTAGE 4V
J 0
(-6875 875);
PAINT SKYBLUE (-6875 875);
DISPLAY INVISIBLE (-6875 875);
FORCEPROP 2 LAST ROOM PVPP_KLM_VR
J 0
(-6875 1025);
PAINT MONO (-6875 1025);
DISPLAY INVISIBLE (-6875 1025);
FORCEPROP 1 LAST PATH I110
J 0
(-6875 1025);
DISPLAY 0.978723 (-6875 1025);
PAINT WHITE (-6875 1025);
DISPLAY INVISIBLE (-6875 1025);
FORCEPROP 2 LAST $SEC 1
J 0
(-6875 1075);
PAINT MONO (-6875 1075);
DISPLAY INVISIBLE (-6875 1075);
FORCEPROP 2 LAST CDS_SEC 1
J 0
(-6875 1075);
PAINT MONO (-6875 1075);
DISPLAY INVISIBLE (-6875 1075);
FORCEPROP 2 LAST BOM_COST MEM_VRD_PVPP_AB
J 0
(-6875 1025);
PAINT MONO (-6875 1025);
DISPLAY INVISIBLE (-6875 1025);
FORCEADD CAP..1
(-6625 875);
FORCEPROP 1 LAST PACK_TYPE 0603LF
J 0
(-6575 675);
DISPLAY 0.617021 (-6575 675);
PAINT SKYBLUE (-6575 675);
FORCEPROP 1 LASTPIN (-6625 775) $PN 2
J 0
(-6615 755);
DISPLAY 0.617021 (-6615 755);
PAINT GREEN (-6615 755);
FORCEPROP 1 LAST LOCATION C4M3
J 0
(-6575 975);
DISPLAY 0.617021 (-6575 975);
PAINT AQUA (-6575 975);
FORCEPROP 1 LAST VALUE 10UF
J 0
(-6575 925);
DISPLAY 0.617021 (-6575 925);
PAINT SKYBLUE (-6575 925);
FORCEPROP 1 LAST TOLERANCE 20%
J 0
(-6575 825);
DISPLAY 0.617021 (-6575 825);
PAINT SKYBLUE (-6575 825);
FORCEPROP 1 LAST MATERIAL X6S
J 0
(-6575 775);
DISPLAY 0.617021 (-6575 775);
PAINT SKYBLUE (-6575 775);
FORCEPROP 1 LASTPIN (-6625 975) $PN 1
J 0
(-6615 955);
DISPLAY 0.617021 (-6615 955);
PAINT GREEN (-6615 955);
FORCEPROP 1 LAST PART_NUMBER E15431-001
J 0
(-6575 725);
DISPLAY 0.617021 (-6575 725);
PAINT BLUE (-6575 725);
FORCEPROP 1 LAST VOLTAGE 4V
J 0
(-6575 875);
PAINT SKYBLUE (-6575 875);
DISPLAY INVISIBLE (-6575 875);
FORCEPROP 2 LAST CDS_LIB mstr_discrete
J 0
(-6625 875);
PAINT MONO (-6625 875);
DISPLAY INVISIBLE (-6625 875);
FORCEPROP 2 LAST CDS_LOCATION C4M3
J 0
(-6575 975);
DISPLAY 0.617021 (-6575 975);
PAINT AQUA (-6575 975);
DISPLAY INVISIBLE (-6575 975);
FORCEPROP 2 LAST BOM_COST MEM_VRD_PVPP_AB
J 0
(-6575 1025);
PAINT MONO (-6575 1025);
DISPLAY INVISIBLE (-6575 1025);
FORCEPROP 2 LAST CDS_SEC 1
J 0
(-6575 1075);
PAINT MONO (-6575 1075);
DISPLAY INVISIBLE (-6575 1075);
FORCEPROP 2 LAST $SEC 1
J 0
(-6575 1075);
PAINT MONO (-6575 1075);
DISPLAY INVISIBLE (-6575 1075);
FORCEPROP 1 LAST PATH I111
J 0
(-6575 1025);
DISPLAY 0.978723 (-6575 1025);
PAINT WHITE (-6575 1025);
DISPLAY INVISIBLE (-6575 1025);
FORCEPROP 2 LAST ROOM PVPP_KLM_VR
J 0
(-6575 1025);
PAINT MONO (-6575 1025);
DISPLAY INVISIBLE (-6575 1025);
FORCEADD CAP..1
(-6325 875);
FORCEPROP 1 LASTPIN (-6325 775) $PN 2
J 0
(-6315 755);
DISPLAY 0.617021 (-6315 755);
PAINT GREEN (-6315 755);
FORCEPROP 1 LASTPIN (-6325 975) $PN 1
J 0
(-6315 955);
DISPLAY 0.617021 (-6315 955);
PAINT GREEN (-6315 955);
FORCEPROP 1 LAST MATERIAL X6S
J 0
(-6275 775);
DISPLAY 0.617021 (-6275 775);
PAINT SKYBLUE (-6275 775);
FORCEPROP 1 LAST TOLERANCE 20%
J 0
(-6275 825);
DISPLAY 0.617021 (-6275 825);
PAINT SKYBLUE (-6275 825);
FORCEPROP 1 LAST VALUE 10UF
J 0
(-6275 925);
DISPLAY 0.617021 (-6275 925);
PAINT SKYBLUE (-6275 925);
FORCEPROP 1 LAST LOCATION C4M4
J 0
(-6275 975);
DISPLAY 0.617021 (-6275 975);
PAINT AQUA (-6275 975);
FORCEPROP 1 LAST PACK_TYPE 0603LF
J 0
(-6275 675);
DISPLAY 0.617021 (-6275 675);
PAINT SKYBLUE (-6275 675);
FORCEPROP 1 LAST PART_NUMBER E15431-001
J 0
(-6275 725);
DISPLAY 0.617021 (-6275 725);
PAINT BLUE (-6275 725);
FORCEPROP 2 LAST CDS_LOCATION C4M4
J 0
(-6275 975);
DISPLAY 0.617021 (-6275 975);
PAINT AQUA (-6275 975);
DISPLAY INVISIBLE (-6275 975);
FORCEPROP 2 LAST CDS_LIB mstr_discrete
J 0
(-6325 875);
PAINT MONO (-6325 875);
DISPLAY INVISIBLE (-6325 875);
FORCEPROP 1 LAST VOLTAGE 4V
J 0
(-6275 875);
PAINT SKYBLUE (-6275 875);
DISPLAY INVISIBLE (-6275 875);
FORCEPROP 2 LAST BOM_COST MEM_VRD_PVPP_AB
J 0
(-6275 1025);
PAINT MONO (-6275 1025);
DISPLAY INVISIBLE (-6275 1025);
FORCEPROP 2 LAST CDS_SEC 1
J 0
(-6275 1075);
PAINT MONO (-6275 1075);
DISPLAY INVISIBLE (-6275 1075);
FORCEPROP 2 LAST $SEC 1
J 0
(-6275 1075);
PAINT MONO (-6275 1075);
DISPLAY INVISIBLE (-6275 1075);
FORCEPROP 1 LAST PATH I125
J 0
(-6275 1025);
DISPLAY 0.978723 (-6275 1025);
PAINT WHITE (-6275 1025);
DISPLAY INVISIBLE (-6275 1025);
FORCEPROP 2 LAST ROOM PVPP_KLM_VR
J 0
(-6275 1025);
PAINT MONO (-6275 1025);
DISPLAY INVISIBLE (-6275 1025);
FORCEADD CAP..1
(-6050 850);
FORCEPROP 1 LASTPIN (-6050 750) $PN 2
J 0
(-6040 730);
DISPLAY 0.617021 (-6040 730);
PAINT GREEN (-6040 730);
FORCEPROP 1 LAST MATERIAL X6S
J 0
(-6000 750);
DISPLAY 0.617021 (-6000 750);
PAINT SKYBLUE (-6000 750);
FORCEPROP 1 LAST TOLERANCE 20%
J 0
(-6000 800);
DISPLAY 0.617021 (-6000 800);
PAINT SKYBLUE (-6000 800);
FORCEPROP 1 LASTPIN (-6050 950) $PN 1
J 0
(-6040 930);
DISPLAY 0.617021 (-6040 930);
PAINT GREEN (-6040 930);
FORCEPROP 1 LAST PACK_TYPE 0603LF
J 0
(-6000 650);
DISPLAY 0.617021 (-6000 650);
PAINT SKYBLUE (-6000 650);
FORCEPROP 1 LAST VALUE 10UF
J 0
(-6000 900);
DISPLAY 0.617021 (-6000 900);
PAINT SKYBLUE (-6000 900);
FORCEPROP 1 LAST PART_NUMBER E15431-001
J 0
(-6000 700);
DISPLAY 0.617021 (-6000 700);
PAINT BLUE (-6000 700);
FORCEPROP 1 LAST LOCATION C6B2
J 0
(-6000 950);
DISPLAY 0.617021 (-6000 950);
PAINT AQUA (-6000 950);
FORCEPROP 1 LAST VOLTAGE 4V
J 0
(-6000 850);
PAINT SKYBLUE (-6000 850);
DISPLAY INVISIBLE (-6000 850);
FORCEPROP 2 LAST CDS_LIB mstr_discrete
J 0
(-6050 850);
PAINT MONO (-6050 850);
DISPLAY INVISIBLE (-6050 850);
FORCEPROP 2 LAST CDS_LOCATION C6B2
J 0
(-6000 950);
DISPLAY 0.617021 (-6000 950);
PAINT AQUA (-6000 950);
DISPLAY INVISIBLE (-6000 950);
FORCEPROP 2 LAST ROOM PVPP_KLM_VR
J 0
(-6000 1000);
PAINT MONO (-6000 1000);
DISPLAY INVISIBLE (-6000 1000);
FORCEPROP 1 LAST PATH I126
J 0
(-6000 1000);
DISPLAY 0.978723 (-6000 1000);
PAINT WHITE (-6000 1000);
DISPLAY INVISIBLE (-6000 1000);
FORCEPROP 2 LAST BOM_COST MEM_VRD_PVPP_AB
J 0
(-6000 1000);
PAINT MONO (-6000 1000);
DISPLAY INVISIBLE (-6000 1000);
FORCEPROP 2 LAST $SEC 1
J 0
(-6000 1050);
PAINT MONO (-6000 1050);
DISPLAY INVISIBLE (-6000 1050);
FORCEPROP 2 LAST CDS_SEC 1
J 0
(-6000 1050);
PAINT MONO (-6000 1050);
DISPLAY INVISIBLE (-6000 1050);
FORCEADD GND..1
(-5600 550);
FORCEPROP 3 LASTPIN (-5600 600) SIG_NAME GND\g
J 0
(-5590 610);
DISPLAY 0.659574 (-5590 610);
PAINT MONO (-5590 610);
DISPLAY INVISIBLE (-5590 610);
FORCEPROP 2 LAST ROOM PVPP_KLM_VR
J 0
(-6150 625);
PAINT ORANGE (-6150 625);
DISPLAY INVISIBLE (-6150 625);
FORCEPROP 1 LAST BODY_TYPE PLUMBING
J 0
(-5645 507);
DISPLAY 0.340426 (-5645 507);
PAINT GREEN (-5645 507);
DISPLAY INVISIBLE (-5645 507);
FORCEPROP 2 LAST BOM_COST MEM_VRD_PVPP_AB
J 0
(-5925 625);
PAINT MONO (-5925 625);
DISPLAY INVISIBLE (-5925 625);
FORCEPROP 1 LAST SIZE 1B
J 0
(-5525 500);
DISPLAY 0.893617 (-5525 500);
PAINT GREEN (-5525 500);
DISPLAY INVISIBLE (-5525 500);
FORCEPROP 2 LAST CDS_LIB mstr_symbols
J 0
(-5600 550);
PAINT MONO (-5600 550);
DISPLAY INVISIBLE (-5600 550);
FORCEPROP 1 LAST VOLTAGE 0
J 0
(-5600 550);
PAINT SKYBLUE (-5600 550);
DISPLAY INVISIBLE (-5600 550);
FORCEPROP 1 LAST PATH I127
J 0
(-5525 550);
DISPLAY 0.872340 (-5525 550);
PAINT AQUA (-5525 550);
DISPLAY INVISIBLE (-5525 550);
FORCEPROP 1 LAST HDL_POWER GND
J 0
(-5600 700);
DISPLAY 0.893617 (-5600 700);
PAINT GREEN (-5600 700);
DISPLAY INVISIBLE (-5600 700);
FORCEADD CAP..1
(-5775 850);
FORCEPROP 1 LASTPIN (-5775 750) $PN 2
J 0
(-5765 730);
DISPLAY 0.617021 (-5765 730);
PAINT GREEN (-5765 730);
FORCEPROP 1 LAST MATERIAL X6S
J 0
(-5725 750);
DISPLAY 0.617021 (-5725 750);
PAINT SKYBLUE (-5725 750);
FORCEPROP 1 LAST TOLERANCE 20%
J 0
(-5725 800);
DISPLAY 0.617021 (-5725 800);
PAINT SKYBLUE (-5725 800);
FORCEPROP 1 LASTPIN (-5775 950) $PN 1
J 0
(-5765 930);
DISPLAY 0.617021 (-5765 930);
PAINT GREEN (-5765 930);
FORCEPROP 1 LAST PACK_TYPE 0603LF
J 0
(-5725 650);
DISPLAY 0.617021 (-5725 650);
PAINT SKYBLUE (-5725 650);
FORCEPROP 1 LAST VALUE 10UF
J 0
(-5725 900);
DISPLAY 0.617021 (-5725 900);
PAINT SKYBLUE (-5725 900);
FORCEPROP 1 LAST PART_NUMBER E15431-001
J 0
(-5725 700);
DISPLAY 0.617021 (-5725 700);
PAINT BLUE (-5725 700);
FORCEPROP 1 LAST LOCATION C6B1
J 0
(-5725 950);
DISPLAY 0.617021 (-5725 950);
PAINT AQUA (-5725 950);
FORCEPROP 1 LAST VOLTAGE 4V
J 0
(-5725 850);
PAINT SKYBLUE (-5725 850);
DISPLAY INVISIBLE (-5725 850);
FORCEPROP 2 LAST CDS_LIB mstr_discrete
J 0
(-5775 850);
PAINT MONO (-5775 850);
DISPLAY INVISIBLE (-5775 850);
FORCEPROP 2 LAST CDS_LOCATION C6B1
J 0
(-5725 950);
DISPLAY 0.617021 (-5725 950);
PAINT AQUA (-5725 950);
DISPLAY INVISIBLE (-5725 950);
FORCEPROP 2 LAST ROOM PVPP_KLM_VR
J 0
(-5725 1000);
PAINT MONO (-5725 1000);
DISPLAY INVISIBLE (-5725 1000);
FORCEPROP 1 LAST PATH I128
J 0
(-5725 1000);
DISPLAY 0.978723 (-5725 1000);
PAINT WHITE (-5725 1000);
DISPLAY INVISIBLE (-5725 1000);
FORCEPROP 2 LAST BOM_COST MEM_VRD_PVPP_AB
J 0
(-5725 1000);
PAINT MONO (-5725 1000);
DISPLAY INVISIBLE (-5725 1000);
FORCEPROP 2 LAST $SEC 1
J 0
(-5725 1050);
PAINT MONO (-5725 1050);
DISPLAY INVISIBLE (-5725 1050);
FORCEPROP 2 LAST CDS_SEC 1
J 0
(-5725 1050);
PAINT MONO (-5725 1050);
DISPLAY INVISIBLE (-5725 1050);
FORCEADD CAP..1
(-5525 875);
FORCEPROP 1 LASTPIN (-5525 775) $PN 2
J 0
(-5515 755);
DISPLAY 0.617021 (-5515 755);
PAINT GREEN (-5515 755);
FORCEPROP 1 LASTPIN (-5525 975) $PN 1
J 0
(-5515 955);
DISPLAY 0.617021 (-5515 955);
PAINT GREEN (-5515 955);
FORCEPROP 1 LAST MATERIAL X6S
J 0
(-5475 775);
DISPLAY 0.617021 (-5475 775);
PAINT SKYBLUE (-5475 775);
FORCEPROP 1 LAST TOLERANCE 20%
J 0
(-5475 825);
DISPLAY 0.617021 (-5475 825);
PAINT SKYBLUE (-5475 825);
FORCEPROP 1 LAST PACK_TYPE 0603LF
J 0
(-5475 675);
DISPLAY 0.617021 (-5475 675);
PAINT SKYBLUE (-5475 675);
FORCEPROP 1 LAST VALUE 10UF
J 0
(-5475 925);
DISPLAY 0.617021 (-5475 925);
PAINT SKYBLUE (-5475 925);
FORCEPROP 1 LAST PART_NUMBER E15431-001
J 0
(-5475 725);
DISPLAY 0.617021 (-5475 725);
PAINT BLUE (-5475 725);
FORCEPROP 1 LAST LOCATION C4L1
J 0
(-5475 975);
DISPLAY 0.617021 (-5475 975);
PAINT AQUA (-5475 975);
FORCEPROP 2 LAST CDS_LOCATION C4L1
J 0
(-5475 975);
DISPLAY 0.617021 (-5475 975);
PAINT AQUA (-5475 975);
DISPLAY INVISIBLE (-5475 975);
FORCEPROP 2 LAST CDS_LIB mstr_discrete
J 0
(-5525 875);
PAINT MONO (-5525 875);
DISPLAY INVISIBLE (-5525 875);
FORCEPROP 1 LAST VOLTAGE 4V
J 0
(-5475 875);
PAINT SKYBLUE (-5475 875);
DISPLAY INVISIBLE (-5475 875);
FORCEPROP 2 LAST ROOM PVPP_KLM_VR
J 0
(-5475 1025);
PAINT MONO (-5475 1025);
DISPLAY INVISIBLE (-5475 1025);
FORCEPROP 1 LAST PATH I129
J 0
(-5475 1025);
DISPLAY 0.978723 (-5475 1025);
PAINT WHITE (-5475 1025);
DISPLAY INVISIBLE (-5475 1025);
FORCEPROP 2 LAST SEC 1
J 0
(-5455 1095);
DISPLAY 0.680851 (-5455 1095);
PAINT MONO (-5455 1095);
DISPLAY INVISIBLE (-5455 1095);
FORCEPROP 2 LAST SEC_TYPE 0603LF
J 0
(-5455 1095);
DISPLAY 1.021277 (-5455 1095);
PAINT ORANGE (-5455 1095);
DISPLAY INVISIBLE (-5455 1095);
FORCEPROP 2 LAST BOM_COST MEM_VRD_PVPP_AB
J 0
(-5475 1025);
PAINT MONO (-5475 1025);
DISPLAY INVISIBLE (-5475 1025);
FORCEADD GND..1
(-1875 675);
FORCEPROP 3 LASTPIN (-1875 725) SIG_NAME GND\g
J 0
(-1865 735);
DISPLAY 0.659574 (-1865 735);
PAINT MONO (-1865 735);
DISPLAY INVISIBLE (-1865 735);
FORCEPROP 2 LAST BOM_COST PVPP_KLM_VR
J 0
(-2725 750);
DISPLAY 1.042553 (-2725 750);
PAINT WHITE (-2725 750);
DISPLAY INVISIBLE (-2725 750);
FORCEPROP 2 LAST ROOM PVPP_KLM_VR
J 0
(-2450 750);
DISPLAY 1.042553 (-2450 750);
PAINT GREEN (-2450 750);
DISPLAY INVISIBLE (-2450 750);
FORCEPROP 1 LAST VOLTAGE 0
J 0
(-1875 675);
PAINT SKYBLUE (-1875 675);
DISPLAY INVISIBLE (-1875 675);
FORCEPROP 2 LAST CDS_LIB mstr_symbols
J 0
(-1875 675);
PAINT MONO (-1875 675);
DISPLAY INVISIBLE (-1875 675);
FORCEPROP 1 LAST SIZE 1B
J 0
(-1800 625);
DISPLAY 0.872340 (-1800 625);
PAINT AQUA (-1800 625);
DISPLAY INVISIBLE (-1800 625);
FORCEPROP 1 LAST BODY_TYPE PLUMBING
J 0
(-1920 632);
DISPLAY 0.340426 (-1920 632);
PAINT GREEN (-1920 632);
DISPLAY INVISIBLE (-1920 632);
FORCEPROP 1 LAST PATH I149
J 0
(-1800 675);
DISPLAY 0.872340 (-1800 675);
PAINT AQUA (-1800 675);
DISPLAY INVISIBLE (-1800 675);
FORCEPROP 1 LAST HDL_POWER GND
J 0
(-1875 825);
DISPLAY 0.872340 (-1875 825);
PAINT GREEN (-1875 825);
DISPLAY INVISIBLE (-1875 825);
FORCEADD RES..1
(-1575 775);
FORCEPROP 1 LAST VALUE 0.0
J 2
(-1600 675);
DISPLAY 0.617021 (-1600 675);
PAINT SKYBLUE (-1600 675);
FORCEPROP 1 LAST WATTAGE 1/16W
J 2
(-1575 625);
DISPLAY 0.617021 (-1575 625);
PAINT SKYBLUE (-1575 625);
FORCEPROP 1 LASTPIN (-1675 775) $PN 1
J 0
(-1663 787);
DISPLAY 0.617021 (-1663 787);
PAINT WHITE (-1663 787);
FORCEPROP 1 LAST MATERIAL CHIP
J 0
(-1575 625);
DISPLAY 0.617021 (-1575 625);
PAINT SKYBLUE (-1575 625);
FORCEPROP 1 LAST PACK_TYPE 0402
J 0
(-1650 575);
DISPLAY 0.617021 (-1650 575);
PAINT SKYBLUE (-1650 575);
FORCEPROP 1 LAST TOLERANCE 5%
J 0
(-1575 675);
DISPLAY 0.617021 (-1575 675);
PAINT SKYBLUE (-1575 675);
FORCEPROP 1 LAST PART_NUMBER G21497-005
J 0
(-1700 725);
DISPLAY 0.617021 (-1700 725);
PAINT BLUE (-1700 725);
FORCEPROP 1 LAST LOCATION R7B20
J 0
(-1625 825);
DISPLAY 0.617021 (-1625 825);
PAINT AQUA (-1625 825);
FORCEPROP 1 LASTPIN (-1475 775) $PN 2
J 0
(-1513 787);
DISPLAY 0.617021 (-1513 787);
PAINT WHITE (-1513 787);
FORCEPROP 2 LAST CDS_LIB mstr_discrete
J 0
(-1575 775);
PAINT MONO (-1575 775);
DISPLAY INVISIBLE (-1575 775);
FORCEPROP 2 LAST CDS_SEC 1
J 0
(-1615 960);
PAINT MONO (-1615 960);
DISPLAY INVISIBLE (-1615 960);
FORCEPROP 2 LAST $SEC 1
J 0
(-1610 980);
PAINT MONO (-1610 980);
DISPLAY INVISIBLE (-1610 980);
FORCEPROP 1 LAST PATH I150
J 0
(-1625 925);
DISPLAY 0.978723 (-1625 925);
PAINT WHITE (-1625 925);
DISPLAY INVISIBLE (-1625 925);
FORCEPROP 2 LAST ROOM PVPP_KLM_VR
J 0
(-1625 850);
PAINT GREEN (-1625 850);
DISPLAY INVISIBLE (-1625 850);
FORCEADD AGND_SCSI..1
(-1325 675);
FORCEPROP 3 LASTPIN (-1325 725) SIG_NAME AGND_PVPP_DEF\g
J 0
(-1315 735);
DISPLAY 0.659574 (-1315 735);
PAINT MONO (-1315 735);
DISPLAY INVISIBLE (-1315 735);
FORCEPROP 1 LAST HDL_POWER AGND_PVPP_DEF
J 1
(-1250 600);
DISPLAY 0.617021 (-1250 600);
PAINT GREEN (-1250 600);
FORCEPROP 1 LAST BODY_TYPE PLUMBING
J 0
(-1370 632);
DISPLAY 0.340426 (-1370 632);
PAINT GREEN (-1370 632);
DISPLAY INVISIBLE (-1370 632);
FORCEPROP 1 LAST VOLTAGE 0.0V
J 0
(-1370 632);
DISPLAY 0.340426 (-1370 632);
PAINT SKYBLUE (-1370 632);
DISPLAY INVISIBLE (-1370 632);
FORCEPROP 2 LAST BOM_COST PVPP_KLM_VR
J 0
(-1475 625);
DISPLAY 1.042553 (-1475 625);
PAINT WHITE (-1475 625);
DISPLAY INVISIBLE (-1475 625);
FORCEPROP 2 LAST CDS_LIB mstr_symbols
J 0
(-1325 675);
PAINT ORANGE (-1325 675);
DISPLAY INVISIBLE (-1325 675);
FORCEPROP 2 LAST ROOM PVPP_KLM_VR
J 0
(-1475 625);
DISPLAY 1.042553 (-1475 625);
PAINT GREEN (-1475 625);
DISPLAY INVISIBLE (-1475 625);
FORCEPROP 1 LAST PATH I151
J 0
(-1250 675);
DISPLAY 0.872340 (-1250 675);
PAINT AQUA (-1250 675);
DISPLAY INVISIBLE (-1250 675);
FORCEADD PVPP_DEF..1
(-1150 3975);
FORCEPROP 3 LASTPIN (-1150 3925) SIG_NAME PVPP_DEF\g
J 0
(-1140 3935);
DISPLAY 0.659574 (-1140 3935);
PAINT MONO (-1140 3935);
DISPLAY INVISIBLE (-1140 3935);
FORCEPROP 1 LAST VOLTAGE 2.5V
J 0
(-1195 3932);
DISPLAY 0.340426 (-1195 3932);
PAINT SKYBLUE (-1195 3932);
DISPLAY INVISIBLE (-1195 3932);
FORCEPROP 1 LAST BODY_TYPE PLUMBING
J 0
(-1195 3932);
DISPLAY 0.340426 (-1195 3932);
PAINT GREEN (-1195 3932);
DISPLAY INVISIBLE (-1195 3932);
FORCEPROP 2 LAST CDS_LIB mstr_symbols
J 0
(-1150 3975);
PAINT ORANGE (-1150 3975);
DISPLAY INVISIBLE (-1150 3975);
FORCEPROP 1 LAST PATH I167
J 0
(-1100 4000);
DISPLAY 0.872340 (-1100 4000);
PAINT AQUA (-1100 4000);
DISPLAY INVISIBLE (-1100 4000);
FORCEPROP 1 LAST HDL_POWER PVPP_DEF
J 1
(-1150 4025);
DISPLAY 0.872340 (-1150 4025);
PAINT GREEN (-1150 4025);
DISPLAY INVISIBLE (-1150 4025);
FORCEPROP 2 LAST ROOM PVPP_KLM_VR
J 0
(-900 4075);
PAINT ORANGE (-900 4075);
DISPLAY INVISIBLE (-900 4075);
FORCEPROP 2 LAST BOM_COST PVPP_KLM_VR
J 0
(-1075 4075);
PAINT MONO (-1075 4075);
DISPLAY INVISIBLE (-1075 4075);
FORCEADD OFFPAGE..1
(-7875 2825);
FORCEPROP 2 LAST $XR0 191 
J 0
(-8157 2825);
DISPLAY 0.638298 (-8157 2825);
PAINT MONO (-8157 2825);
FORCEPROP 2 LAST $XR1 231 
J 0
(-8277 2825);
DISPLAY 0.638298 (-8277 2825);
PAINT MONO (-8277 2825);
FORCEPROP 2 LAST BOM_COST PVPP_KLM_VR
J 0
(-8700 2900);
DISPLAY 1.042553 (-8700 2900);
PAINT WHITE (-8700 2900);
DISPLAY INVISIBLE (-8700 2900);
FORCEPROP 2 LAST ROOM PVPP_KLM_VR
J 0
(-8425 2900);
DISPLAY 1.042553 (-8425 2900);
PAINT GREEN (-8425 2900);
DISPLAY INVISIBLE (-8425 2900);
FORCEPROP 2 LAST PATH I181
J 0
(-8125 2875);
DISPLAY 1.021277 (-8125 2875);
PAINT ORANGE (-8125 2875);
DISPLAY INVISIBLE (-8125 2875);
FORCEPROP 0 LAST TOLERANCE 1%
J 0
(-7825 2900);
PAINT SKYBLUE (-7825 2900);
DISPLAY INVISIBLE (-7825 2900);
FORCEPROP 1 LAST COMMENT_BODY TRUE
J 0
(-7750 2725);
DISPLAY 0.872340 (-7750 2725);
PAINT PEACH (-7750 2725);
DISPLAY INVISIBLE (-7750 2725);
FORCEPROP 2 LAST CDS_LIB mstr_standard
J 0
(-7875 2825);
PAINT MONO (-7875 2825);
DISPLAY INVISIBLE (-7875 2825);
FORCEPROP 1 LAST OFFPAGE TRUE
J 0
(-7550 2700);
PAINT GREEN (-7550 2700);
DISPLAY INVISIBLE (-7550 2700);
FORCEADD CAP..1
R 2
(-6825 2500);
FORCEPROP 1 LAST VOLTAGE 50V
J 2
(-6875 2500);
DISPLAY 0.617021 (-6875 2500);
PAINT SKYBLUE (-6875 2500);
FORCEPROP 1 LAST PACK_TYPE 0402LF
J 2
(-6875 2300);
DISPLAY 0.617021 (-6875 2300);
PAINT SKYBLUE (-6875 2300);
FORCEPROP 1 LAST TOLERANCE 10%
J 2
(-6875 2450);
DISPLAY 0.617021 (-6875 2450);
PAINT SKYBLUE (-6875 2450);
FORCEPROP 1 LAST PART_NUMBER A36096-046
J 2
(-6850 2350);
DISPLAY 0.617021 (-6850 2350);
PAINT BLUE (-6850 2350);
FORCEPROP 1 LAST MATERIAL EMPTY
J 2
(-6875 2400);
DISPLAY 0.617021 (-6875 2400);
PAINT RED (-6875 2400);
FORCEPROP 1 LASTPIN (-6825 2400) $PN 2
J 2
(-6835 2380);
DISPLAY 0.617021 (-6835 2380);
PAINT WHITE (-6835 2380);
FORCEPROP 1 LAST VALUE 1000PF
J 2
(-6875 2550);
DISPLAY 0.617021 (-6875 2550);
PAINT SKYBLUE (-6875 2550);
FORCEPROP 1 LAST LOCATION C7B9
J 2
(-6875 2600);
DISPLAY 0.617021 (-6875 2600);
PAINT AQUA (-6875 2600);
FORCEPROP 1 LASTPIN (-6825 2600) $PN 1
J 2
(-6835 2580);
DISPLAY 0.617021 (-6835 2580);
PAINT WHITE (-6835 2580);
FORCEPROP 2 LAST ROOM PVPP_KLM_VR
J 2
(-6825 2500);
PAINT GREEN (-6825 2500);
DISPLAY INVISIBLE (-6825 2500);
FORCEPROP 2 LAST BOM_COST PVPP_KLM_VR
J 2
(-6825 2500);
PAINT WHITE (-6825 2500);
DISPLAY INVISIBLE (-6825 2500);
FORCEPROP 2 LAST CDS_LIB mstr_discrete
J 2
(-6825 2500);
PAINT MONO (-6825 2500);
DISPLAY INVISIBLE (-6825 2500);
FORCEPROP 1 LAST PATH I185
J 2
(-6875 2650);
DISPLAY 0.978723 (-6875 2650);
PAINT WHITE (-6875 2650);
DISPLAY INVISIBLE (-6875 2650);
FORCEPROP 2 LAST CDS_LOCATION C7B9
J 2
(-6875 2600);
DISPLAY 0.617021 (-6875 2600);
PAINT AQUA (-6875 2600);
DISPLAY INVISIBLE (-6875 2600);
FORCEPROP 2 LAST $SEC 1
J 2
(-6875 2700);
DISPLAY 0.680851 (-6875 2700);
PAINT MONO (-6875 2700);
DISPLAY INVISIBLE (-6875 2700);
FORCEPROP 2 LAST CDS_SEC 1
J 2
(-6875 2700);
DISPLAY 1.042553 (-6875 2700);
PAINT ORANGE (-6875 2700);
DISPLAY INVISIBLE (-6875 2700);
FORCEPROP 0 LAST REUSE_ID 1
J 2
(-6875 2700);
DISPLAY 1.042553 (-6875 2700);
PAINT ORANGE (-6875 2700);
DISPLAY INVISIBLE (-6875 2700);
FORCEPROP 0 LAST FIN VR_1P2
J 2
(-6875 2800);
PAINT ORANGE (-6875 2800);
DISPLAY INVISIBLE (-6875 2800);
FORCEADD RES..2
R 2
(-5100 1650);
FORCEPROP 1 LAST PACK_TYPE 0402
J 2
(-5140 1475);
DISPLAY 0.617021 (-5140 1475);
PAINT SKYBLUE (-5140 1475);
FORCEPROP 1 LAST PART_NUMBER G21796-242
J 2
(-5140 1525);
DISPLAY 0.617021 (-5140 1525);
PAINT BLUE (-5140 1525);
FORCEPROP 1 LAST WATTAGE 1/16W
J 2
(-5140 1625);
DISPLAY 0.617021 (-5140 1625);
PAINT SKYBLUE (-5140 1625);
FORCEPROP 1 LAST MATERIAL CHIP
J 2
(-5140 1575);
DISPLAY 0.617021 (-5140 1575);
PAINT SKYBLUE (-5140 1575);
FORCEPROP 1 LAST TOLERANCE 1.0%
J 2
(-5145 1675);
DISPLAY 0.617021 (-5145 1675);
PAINT SKYBLUE (-5145 1675);
FORCEPROP 1 LAST VALUE 7.87K
J 2
(-5145 1725);
DISPLAY 0.617021 (-5145 1725);
PAINT SKYBLUE (-5145 1725);
FORCEPROP 1 LAST LOCATION R7B14
J 2
(-5145 1775);
DISPLAY 0.617021 (-5145 1775);
PAINT AQUA (-5145 1775);
FORCEPROP 1 LASTPIN (-5100 1750) $PN 1
J 2
(-5105 1712);
DISPLAY 0.617021 (-5105 1712);
PAINT WHITE (-5105 1712);
FORCEPROP 1 LASTPIN (-5100 1550) $PN 2
J 2
(-5105 1560);
DISPLAY 0.617021 (-5105 1560);
PAINT WHITE (-5105 1560);
FORCEPROP 1 LAST PATH I193
J 2
(-5150 1825);
DISPLAY 0.978723 (-5150 1825);
PAINT WHITE (-5150 1825);
DISPLAY INVISIBLE (-5150 1825);
FORCEPROP 2 LAST CDS_LOCATION R7B14
J 2
(-5145 1775);
DISPLAY 0.617021 (-5145 1775);
PAINT AQUA (-5145 1775);
DISPLAY INVISIBLE (-5145 1775);
FORCEPROP 2 LAST $SEC 1
J 0
(-5150 1875);
DISPLAY 0.680851 (-5150 1875);
PAINT MONO (-5150 1875);
DISPLAY INVISIBLE (-5150 1875);
FORCEPROP 2 LAST BOM_COST PVPP_KLM_VR
J 2
(-5100 1650);
PAINT WHITE (-5100 1650);
DISPLAY INVISIBLE (-5100 1650);
FORCEPROP 2 LAST CDS_LIB mstr_discrete
J 2
(-5100 1650);
PAINT MONO (-5100 1650);
DISPLAY INVISIBLE (-5100 1650);
FORCEPROP 2 LAST ROOM PVPP_KLM_VR
J 2
(-5100 1650);
PAINT GREEN (-5100 1650);
DISPLAY INVISIBLE (-5100 1650);
FORCEPROP 2 LAST CDS_SEC 1
J 2
(-5000 2025);
DISPLAY 1.042553 (-5000 2025);
PAINT ORANGE (-5000 2025);
DISPLAY INVISIBLE (-5000 2025);
FORCEADD CAP..1
(-5425 2175);
FORCEPROP 1 LAST MATERIAL X7R
J 0
(-5375 1975);
DISPLAY 0.617021 (-5375 1975);
PAINT SKYBLUE (-5375 1975);
FORCEPROP 1 LAST PART_NUMBER A36096-129
J 0
(-5400 2025);
DISPLAY 0.617021 (-5400 2025);
PAINT BLUE (-5400 2025);
FORCEPROP 1 LASTPIN (-5425 2275) $PN 1
J 0
(-5415 2255);
DISPLAY 0.617021 (-5415 2255);
PAINT ORANGE (-5415 2255);
FORCEPROP 1 LASTPIN (-5425 2075) $PN 2
J 0
(-5415 2055);
DISPLAY 0.617021 (-5415 2055);
PAINT ORANGE (-5415 2055);
FORCEPROP 1 LAST VOLTAGE 16V
J 0
(-5350 2175);
DISPLAY 0.617021 (-5350 2175);
PAINT SKYBLUE (-5350 2175);
FORCEPROP 1 LAST PACK_TYPE 0402
J 0
(-5375 2075);
DISPLAY 0.617021 (-5375 2075);
PAINT SKYBLUE (-5375 2075);
FORCEPROP 1 LAST TOLERANCE 10%
J 0
(-5350 2125);
DISPLAY 0.617021 (-5350 2125);
PAINT SKYBLUE (-5350 2125);
FORCEPROP 1 LAST VALUE 0.027UF
J 0
(-5375 2225);
DISPLAY 0.617021 (-5375 2225);
PAINT SKYBLUE (-5375 2225);
FORCEPROP 1 LAST LOCATION C7B11
J 0
(-5375 2275);
DISPLAY 0.617021 (-5375 2275);
PAINT AQUA (-5375 2275);
FORCEPROP 2 LAST CDS_LIB mstr_discrete
J 0
(-5425 2175);
PAINT MONO (-5425 2175);
DISPLAY INVISIBLE (-5425 2175);
FORCEPROP 2 LAST ROOM PVPP_KLM_VR
J 0
(-5375 2300);
PAINT GREEN (-5375 2300);
DISPLAY INVISIBLE (-5375 2300);
FORCEPROP 1 LAST PATH I197
J 0
(-5375 2325);
DISPLAY 0.978723 (-5375 2325);
PAINT WHITE (-5375 2325);
DISPLAY INVISIBLE (-5375 2325);
FORCEPROP 2 LAST CDS_LOCATION C7B11
J 0
(-5375 2275);
DISPLAY 0.617021 (-5375 2275);
PAINT AQUA (-5375 2275);
DISPLAY INVISIBLE (-5375 2275);
FORCEPROP 2 LAST SEC 1
J 0
(-5375 2375);
DISPLAY 0.680851 (-5375 2375);
PAINT MONO (-5375 2375);
DISPLAY INVISIBLE (-5375 2375);
FORCEPROP 2 LAST BOM_COST PVPP_KLM_VR
J 0
(-5375 2325);
DISPLAY 1.042553 (-5375 2325);
PAINT WHITE (-5375 2325);
DISPLAY INVISIBLE (-5375 2325);
FORCEPROP 2 LAST REUSE_ID 26
J 0
(-5375 2375);
DISPLAY 1.042553 (-5375 2375);
PAINT ORANGE (-5375 2375);
DISPLAY INVISIBLE (-5375 2375);
FORCEPROP 2 LAST SEC_TYPE 0402
J 0
(-5375 2375);
DISPLAY 1.021277 (-5375 2375);
PAINT ORANGE (-5375 2375);
DISPLAY INVISIBLE (-5375 2375);
FORCEADD GND..1
(-5300 3825);
FORCEPROP 3 LASTPIN (-5300 3875) SIG_NAME GND\g
J 0
(-5290 3885);
DISPLAY 0.659574 (-5290 3885);
PAINT MONO (-5290 3885);
DISPLAY INVISIBLE (-5290 3885);
FORCEPROP 2 LAST BOM_COST PVPP_KLM_VR
J 0
(-6150 3900);
DISPLAY 1.042553 (-6150 3900);
PAINT WHITE (-6150 3900);
DISPLAY INVISIBLE (-6150 3900);
FORCEPROP 2 LAST ROOM PVPP_KLM_VR
J 0
(-5875 3900);
DISPLAY 1.042553 (-5875 3900);
PAINT GREEN (-5875 3900);
DISPLAY INVISIBLE (-5875 3900);
FORCEPROP 1 LAST BODY_TYPE PLUMBING
J 0
(-5345 3782);
DISPLAY 0.340426 (-5345 3782);
PAINT GREEN (-5345 3782);
DISPLAY INVISIBLE (-5345 3782);
FORCEPROP 1 LAST SIZE 1B
J 0
(-5225 3775);
DISPLAY 0.872340 (-5225 3775);
PAINT GREEN (-5225 3775);
DISPLAY INVISIBLE (-5225 3775);
FORCEPROP 1 LAST VOLTAGE 0
J 0
(-5300 3825);
PAINT SKYBLUE (-5300 3825);
DISPLAY INVISIBLE (-5300 3825);
FORCEPROP 2 LAST CDS_LIB mstr_symbols
J 0
(-5300 3825);
PAINT MONO (-5300 3825);
DISPLAY INVISIBLE (-5300 3825);
FORCEPROP 1 LAST PATH I198
J 0
(-5225 3825);
DISPLAY 0.872340 (-5225 3825);
PAINT AQUA (-5225 3825);
DISPLAY INVISIBLE (-5225 3825);
FORCEPROP 1 LAST HDL_POWER GND
J 0
(-5300 3975);
DISPLAY 0.872340 (-5300 3975);
PAINT GREEN (-5300 3975);
DISPLAY INVISIBLE (-5300 3975);
FORCEADD P12V_STBY..1
(-7950 4500);
FORCEPROP 3 LASTPIN (-7950 4450) SIG_NAME P12V_STBY\g
J 0
(-7940 4460);
DISPLAY 0.659574 (-7940 4460);
PAINT MONO (-7940 4460);
DISPLAY INVISIBLE (-7940 4460);
FORCEPROP 1 LAST HDL_POWER P12V_STBY
J 0
(-8250 4375);
DISPLAY 0.872340 (-8250 4375);
PAINT ORANGE (-8250 4375);
DISPLAY INVISIBLE (-8250 4375);
FORCEPROP 1 LAST BODY_TYPE PLUMBING
J 0
(-7995 4457);
DISPLAY 0.340426 (-7995 4457);
PAINT GREEN (-7995 4457);
DISPLAY INVISIBLE (-7995 4457);
FORCEPROP 2 LAST CDS_LIB mstr_symbols
J 0
(-7950 4500);
PAINT ORANGE (-7950 4500);
DISPLAY INVISIBLE (-7950 4500);
FORCEPROP 1 LAST VOLTAGE 12.0V
J 0
(-7995 4457);
DISPLAY 0.340426 (-7995 4457);
PAINT SKYBLUE (-7995 4457);
DISPLAY INVISIBLE (-7995 4457);
FORCEPROP 1 LAST PATH I199
J 0
(-7905 4502);
DISPLAY 0.340426 (-7905 4502);
PAINT GREEN (-7905 4502);
DISPLAY INVISIBLE (-7905 4502);
FORCEPROP 1 LAST SIZE 1B
J 0
(-7905 4522);
DISPLAY 0.340426 (-7905 4522);
PAINT GREEN (-7905 4522);
DISPLAY INVISIBLE (-7905 4522);
FORCEADD FERRITE..1
(-7725 4300);
FORCEPROP 1 LAST VALUE 22
J 2
(-7745 4200);
DISPLAY 0.617021 (-7745 4200);
PAINT SKYBLUE (-7745 4200);
FORCEPROP 1 LASTPIN (-7825 4300) $PN 1
J 2
(-7790 4310);
DISPLAY 0.617021 (-7790 4310);
PAINT WHITE (-7790 4310);
FORCEPROP 1 LAST MATERIAL FB
J 0
(-7720 4200);
DISPLAY 0.617021 (-7720 4200);
PAINT SKYBLUE (-7720 4200);
FORCEPROP 1 LAST PART_NUMBER 656554-051
J 0
(-7820 4415);
DISPLAY 0.617021 (-7820 4415);
PAINT BLUE (-7820 4415);
FORCEPROP 1 LAST LOCATION FB7B1
J 0
(-7820 4355);
DISPLAY 0.617021 (-7820 4355);
PAINT AQUA (-7820 4355);
FORCEPROP 1 LASTPIN (-7625 4300) $PN 2
J 0
(-7645 4310);
DISPLAY 0.617021 (-7645 4310);
PAINT WHITE (-7645 4310);
FORCEPROP 1 LAST PACK_TYPE SM
J 0
(-7645 4200);
DISPLAY 0.617021 (-7645 4200);
PAINT SKYBLUE (-7645 4200);
FORCEPROP 2 LAST CDS_LIB mstr_discrete
J 0
(-7725 4300);
PAINT MONO (-7725 4300);
DISPLAY INVISIBLE (-7725 4300);
FORCEPROP 0 LAST TOLERANCE 1%
J 0
(-7800 4450);
PAINT SKYBLUE (-7800 4450);
DISPLAY INVISIBLE (-7800 4450);
FORCEPROP 2 LAST SEC_TYPE SM
J 0
(-7800 4525);
DISPLAY 1.659574 (-7800 4525);
PAINT ORANGE (-7800 4525);
DISPLAY INVISIBLE (-7800 4525);
FORCEPROP 2 LAST SEC 1
J 0
(-7800 4525);
DISPLAY 1.106383 (-7800 4525);
PAINT MONO (-7800 4525);
DISPLAY INVISIBLE (-7800 4525);
FORCEPROP 2 LAST CDS_LOCATION FB7B1
J 0
(-7820 4355);
DISPLAY 0.617021 (-7820 4355);
PAINT AQUA (-7820 4355);
DISPLAY INVISIBLE (-7820 4355);
FORCEPROP 1 LAST PATH I200
J 0
(-7820 4465);
DISPLAY 0.872340 (-7820 4465);
PAINT PURPLE (-7820 4465);
DISPLAY INVISIBLE (-7820 4465);
FORCEPROP 2 LAST ROOM PVPP_KLM_VR
J 0
(-7800 4450);
DISPLAY 1.659574 (-7800 4450);
PAINT GREEN (-7800 4450);
DISPLAY INVISIBLE (-7800 4450);
FORCEADD GND..1
(-7375 3900);
FORCEPROP 3 LASTPIN (-7375 3950) SIG_NAME GND\g
J 0
(-7365 3960);
DISPLAY 0.659574 (-7365 3960);
PAINT MONO (-7365 3960);
DISPLAY INVISIBLE (-7365 3960);
FORCEPROP 2 LAST BOM_COST PVPP_KLM_VR
J 0
(-8225 3975);
DISPLAY 1.042553 (-8225 3975);
PAINT WHITE (-8225 3975);
DISPLAY INVISIBLE (-8225 3975);
FORCEPROP 2 LAST ROOM PVPP_KLM_VR
J 0
(-7950 3975);
DISPLAY 1.042553 (-7950 3975);
PAINT GREEN (-7950 3975);
DISPLAY INVISIBLE (-7950 3975);
FORCEPROP 1 LAST VOLTAGE 0
J 0
(-7375 3900);
PAINT SKYBLUE (-7375 3900);
DISPLAY INVISIBLE (-7375 3900);
FORCEPROP 1 LAST SIZE 1B
J 0
(-7300 3850);
DISPLAY 0.872340 (-7300 3850);
PAINT GREEN (-7300 3850);
DISPLAY INVISIBLE (-7300 3850);
FORCEPROP 2 LAST CDS_LIB mstr_symbols
J 0
(-7375 3900);
PAINT MONO (-7375 3900);
DISPLAY INVISIBLE (-7375 3900);
FORCEPROP 1 LAST BODY_TYPE PLUMBING
J 0
(-7420 3857);
DISPLAY 0.340426 (-7420 3857);
PAINT GREEN (-7420 3857);
DISPLAY INVISIBLE (-7420 3857);
FORCEPROP 1 LAST PATH I201
J 0
(-7300 3900);
DISPLAY 0.872340 (-7300 3900);
PAINT AQUA (-7300 3900);
DISPLAY INVISIBLE (-7300 3900);
FORCEPROP 1 LAST HDL_POWER GND
J 0
(-7375 4050);
DISPLAY 0.872340 (-7375 4050);
PAINT GREEN (-7375 4050);
DISPLAY INVISIBLE (-7375 4050);
FORCEADD CAP..1
(-7375 4125);
FORCEPROP 1 LASTPIN (-7375 4025) $PN 2
J 0
(-7365 4005);
DISPLAY 0.617021 (-7365 4005);
PAINT WHITE (-7365 4005);
FORCEPROP 1 LAST PACK_TYPE 1210
J 0
(-7325 3925);
DISPLAY 0.617021 (-7325 3925);
PAINT SKYBLUE (-7325 3925);
FORCEPROP 1 LAST MATERIAL X6S
J 0
(-7325 4025);
DISPLAY 0.617021 (-7325 4025);
PAINT SKYBLUE (-7325 4025);
FORCEPROP 1 LAST PART_NUMBER D38464-007
J 0
(-7325 3975);
DISPLAY 0.617021 (-7325 3975);
PAINT BLUE (-7325 3975);
FORCEPROP 1 LAST TOLERANCE 20%
J 0
(-7325 4075);
DISPLAY 0.617021 (-7325 4075);
PAINT SKYBLUE (-7325 4075);
FORCEPROP 1 LASTPIN (-7375 4225) $PN 1
J 0
(-7365 4205);
DISPLAY 0.617021 (-7365 4205);
PAINT WHITE (-7365 4205);
FORCEPROP 1 LAST VOLTAGE 16V
J 0
(-7325 4125);
DISPLAY 0.617021 (-7325 4125);
PAINT SKYBLUE (-7325 4125);
FORCEPROP 1 LAST VALUE 47UF
J 0
(-7325 4175);
DISPLAY 0.617021 (-7325 4175);
PAINT SKYBLUE (-7325 4175);
FORCEPROP 1 LAST LOCATION C7B8
J 0
(-7325 4225);
DISPLAY 0.617021 (-7325 4225);
PAINT AQUA (-7325 4225);
FORCEPROP 2 LAST CDS_LIB mstr_discrete
J 0
(-7375 4125);
PAINT MONO (-7375 4125);
DISPLAY INVISIBLE (-7375 4125);
FORCEPROP 2 LAST BOM_COST PVPP_KLM_VR
J 0
(-7375 4125);
PAINT WHITE (-7375 4125);
DISPLAY INVISIBLE (-7375 4125);
FORCEPROP 2 LAST ROOM PVPP_KLM_VR
J 0
(-7375 4125);
PAINT GREEN (-7375 4125);
DISPLAY INVISIBLE (-7375 4125);
FORCEPROP 2 LAST CDS_LOCATION C7B8
J 0
(-7325 4225);
DISPLAY 0.617021 (-7325 4225);
PAINT AQUA (-7325 4225);
DISPLAY INVISIBLE (-7325 4225);
FORCEPROP 1 LAST PATH I202
J 0
(-7325 4275);
DISPLAY 0.978723 (-7325 4275);
PAINT WHITE (-7325 4275);
DISPLAY INVISIBLE (-7325 4275);
FORCEPROP 2 LAST CDS_SEC 1
J 0
(-7325 4325);
DISPLAY 1.042553 (-7325 4325);
PAINT ORANGE (-7325 4325);
DISPLAY INVISIBLE (-7325 4325);
FORCEPROP 2 LAST $SEC 1
J 0
(-7325 4325);
DISPLAY 0.680851 (-7325 4325);
PAINT MONO (-7325 4325);
DISPLAY INVISIBLE (-7325 4325);
FORCEADD CAP..1
(-5300 4150);
FORCEPROP 1 LAST PACK_TYPE 0402
J 0
(-5250 3950);
DISPLAY 0.617021 (-5250 3950);
PAINT SKYBLUE (-5250 3950);
FORCEPROP 1 LAST MATERIAL X6S
J 0
(-5250 4050);
DISPLAY 0.617021 (-5250 4050);
PAINT SKYBLUE (-5250 4050);
FORCEPROP 1 LASTPIN (-5300 4050) $PN 2
J 0
(-5290 4030);
DISPLAY 0.617021 (-5290 4030);
PAINT WHITE (-5290 4030);
FORCEPROP 1 LAST PART_NUMBER D97712-011
J 0
(-5250 4000);
DISPLAY 0.617021 (-5250 4000);
PAINT BLUE (-5250 4000);
FORCEPROP 1 LASTPIN (-5300 4250) $PN 1
J 0
(-5290 4230);
DISPLAY 0.617021 (-5290 4230);
PAINT WHITE (-5290 4230);
FORCEPROP 1 LAST LOCATION C3M9
J 0
(-5250 4250);
DISPLAY 0.617021 (-5250 4250);
PAINT AQUA (-5250 4250);
FORCEPROP 1 LAST VOLTAGE 16V
J 0
(-5250 4150);
DISPLAY 0.617021 (-5250 4150);
PAINT SKYBLUE (-5250 4150);
FORCEPROP 1 LAST TOLERANCE 10%
J 0
(-5250 4100);
DISPLAY 0.617021 (-5250 4100);
PAINT SKYBLUE (-5250 4100);
FORCEPROP 1 LAST VALUE 1.0UF
J 0
(-5250 4200);
DISPLAY 0.617021 (-5250 4200);
PAINT SKYBLUE (-5250 4200);
FORCEPROP 2 LAST ROOM PVPP_KLM_VR
J 0
(-5300 4150);
PAINT GREEN (-5300 4150);
DISPLAY INVISIBLE (-5300 4150);
FORCEPROP 2 LAST CDS_LIB mstr_discrete
J 0
(-5300 4150);
PAINT MONO (-5300 4150);
DISPLAY INVISIBLE (-5300 4150);
FORCEPROP 2 LAST BOM_COST PVPP_KLM_VR
J 0
(-5300 4150);
PAINT WHITE (-5300 4150);
DISPLAY INVISIBLE (-5300 4150);
FORCEPROP 1 LAST PATH I207
J 0
(-5250 4300);
DISPLAY 0.978723 (-5250 4300);
PAINT WHITE (-5250 4300);
DISPLAY INVISIBLE (-5250 4300);
FORCEPROP 2 LAST CDS_LOCATION C3M9
J 0
(-5250 4250);
DISPLAY 0.617021 (-5250 4250);
PAINT AQUA (-5250 4250);
DISPLAY INVISIBLE (-5250 4250);
FORCEPROP 2 LAST CDS_SEC 1
J 0
(-5250 4350);
DISPLAY 1.042553 (-5250 4350);
PAINT ORANGE (-5250 4350);
DISPLAY INVISIBLE (-5250 4350);
FORCEPROP 2 LAST $SEC 1
J 0
(-5250 4350);
DISPLAY 0.680851 (-5250 4350);
PAINT MONO (-5250 4350);
DISPLAY INVISIBLE (-5250 4350);
FORCEPROP 0 LAST REUSE_ID 1
J 0
(-5250 4350);
DISPLAY 1.042553 (-5250 4350);
PAINT ORANGE (-5250 4350);
DISPLAY INVISIBLE (-5250 4350);
FORCEPROP 0 LAST FIN VR_1P2
J 0
(-5250 4450);
PAINT ORANGE (-5250 4450);
DISPLAY INVISIBLE (-5250 4450);
FORCEADD GND..1
(-4225 475);
FORCEPROP 3 LASTPIN (-4225 525) SIG_NAME GND\g
J 0
(-4215 535);
DISPLAY 0.659574 (-4215 535);
PAINT MONO (-4215 535);
DISPLAY INVISIBLE (-4215 535);
FORCEPROP 2 LAST BOM_COST PVPP_KLM_VR
J 0
(-5125 625);
DISPLAY 1.042553 (-5125 625);
PAINT WHITE (-5125 625);
DISPLAY INVISIBLE (-5125 625);
FORCEPROP 2 LAST ROOM PVPP_KLM_VR
J 0
(-4875 625);
PAINT GREEN (-4875 625);
DISPLAY INVISIBLE (-4875 625);
FORCEPROP 1 LAST PATH I208
J 0
(-4150 475);
DISPLAY 0.872340 (-4150 475);
PAINT AQUA (-4150 475);
DISPLAY INVISIBLE (-4150 475);
FORCEPROP 1 LAST BODY_TYPE PLUMBING
J 0
(-4270 432);
DISPLAY 0.340426 (-4270 432);
PAINT GREEN (-4270 432);
DISPLAY INVISIBLE (-4270 432);
FORCEPROP 1 LAST SIZE 1B
J 0
(-4150 500);
DISPLAY 0.893617 (-4150 500);
PAINT GREEN (-4150 500);
DISPLAY INVISIBLE (-4150 500);
FORCEPROP 1 LAST VOLTAGE 0
J 0
(-4225 550);
PAINT SKYBLUE (-4225 550);
DISPLAY INVISIBLE (-4225 550);
FORCEPROP 2 LAST CDS_LIB mstr_symbols
J 0
(-4225 550);
PAINT MONO (-4225 550);
DISPLAY INVISIBLE (-4225 550);
FORCEPROP 1 LAST HDL_POWER GND
J 0
(-4225 700);
DISPLAY 0.893617 (-4225 700);
PAINT GREEN (-4225 700);
DISPLAY INVISIBLE (-4225 700);
FORCEADD CAP..1
(-4225 725);
FORCEPROP 1 LASTPIN (-4225 625) $PN 2
J 0
(-4215 605);
DISPLAY 0.617021 (-4215 605);
PAINT WHITE (-4215 605);
FORCEPROP 1 LASTPIN (-4225 825) $PN 1
J 0
(-4215 805);
DISPLAY 0.617021 (-4215 805);
PAINT WHITE (-4215 805);
FORCEPROP 1 LAST MATERIAL X7R
J 0
(-4175 625);
DISPLAY 0.617021 (-4175 625);
PAINT SKYBLUE (-4175 625);
FORCEPROP 1 LAST VOLTAGE 50V
J 0
(-4175 725);
DISPLAY 0.617021 (-4175 725);
PAINT SKYBLUE (-4175 725);
FORCEPROP 1 LAST PACK_TYPE 0402LF
J 0
(-4175 575);
DISPLAY 0.617021 (-4175 575);
PAINT SKYBLUE (-4175 575);
FORCEPROP 1 LAST TOLERANCE 10%
J 0
(-4175 675);
DISPLAY 0.617021 (-4175 675);
PAINT SKYBLUE (-4175 675);
FORCEPROP 1 LAST VALUE 1000PF
J 0
(-4175 775);
DISPLAY 0.617021 (-4175 775);
PAINT SKYBLUE (-4175 775);
FORCEPROP 1 LAST PART_NUMBER A36096-046
J 0
(-4175 525);
DISPLAY 0.617021 (-4175 525);
PAINT BLUE (-4175 525);
FORCEPROP 1 LAST LOCATION C7B12
J 0
(-4175 825);
DISPLAY 0.617021 (-4175 825);
PAINT AQUA (-4175 825);
FORCEPROP 2 LAST ROOM PVPP_KLM_VR
J 0
(-4225 725);
PAINT GREEN (-4225 725);
DISPLAY INVISIBLE (-4225 725);
FORCEPROP 2 LAST BOM_COST PVPP_KLM_VR
J 0
(-4225 725);
PAINT WHITE (-4225 725);
DISPLAY INVISIBLE (-4225 725);
FORCEPROP 2 LAST CDS_LIB mstr_discrete
J 2
(-4225 725);
PAINT MONO (-4225 725);
DISPLAY INVISIBLE (-4225 725);
FORCEPROP 1 LAST PATH I209
J 0
(-4175 875);
DISPLAY 0.978723 (-4175 875);
PAINT WHITE (-4175 875);
DISPLAY INVISIBLE (-4175 875);
FORCEPROP 2 LAST CDS_LOCATION C7B12
J 0
(-4175 825);
DISPLAY 0.617021 (-4175 825);
PAINT AQUA (-4175 825);
DISPLAY INVISIBLE (-4175 825);
FORCEPROP 2 LAST CDS_SEC 1
J 2
(-4175 925);
DISPLAY 1.042553 (-4175 925);
PAINT ORANGE (-4175 925);
DISPLAY INVISIBLE (-4175 925);
FORCEPROP 2 LAST $SEC 1
J 2
(-4175 925);
DISPLAY 0.680851 (-4175 925);
PAINT MONO (-4175 925);
DISPLAY INVISIBLE (-4175 925);
FORCEPROP 2 LAST REUSE_ID 17
J 0
(-4175 925);
DISPLAY 1.042553 (-4175 925);
PAINT ORANGE (-4175 925);
DISPLAY INVISIBLE (-4175 925);
FORCEADD RES..2
(-4575 1250);
FORCEPROP 1 LASTPIN (-4575 1150) $PN 2
J 0
(-4570 1160);
DISPLAY 0.617021 (-4570 1160);
PAINT WHITE (-4570 1160);
FORCEPROP 1 LAST WATTAGE 1/16W
J 0
(-4535 1225);
DISPLAY 0.617021 (-4535 1225);
PAINT SKYBLUE (-4535 1225);
FORCEPROP 1 LAST MATERIAL CHIP
J 0
(-4535 1175);
DISPLAY 0.617021 (-4535 1175);
PAINT SKYBLUE (-4535 1175);
FORCEPROP 1 LAST PACK_TYPE 0402
J 0
(-4535 1075);
DISPLAY 0.617021 (-4535 1075);
PAINT SKYBLUE (-4535 1075);
FORCEPROP 1 LAST TOLERANCE 1%
J 0
(-4530 1275);
DISPLAY 0.617021 (-4530 1275);
PAINT SKYBLUE (-4530 1275);
FORCEPROP 1 LASTPIN (-4575 1350) $PN 1
J 0
(-4570 1312);
DISPLAY 0.617021 (-4570 1312);
PAINT WHITE (-4570 1312);
FORCEPROP 1 LAST VALUE 1.00K
J 0
(-4530 1325);
DISPLAY 0.617021 (-4530 1325);
PAINT SKYBLUE (-4530 1325);
FORCEPROP 1 LAST LOCATION R7B17
J 0
(-4530 1375);
DISPLAY 0.617021 (-4530 1375);
PAINT AQUA (-4530 1375);
FORCEPROP 1 LAST PART_NUMBER G21796-026
J 0
(-4535 1125);
DISPLAY 0.617021 (-4535 1125);
PAINT BLUE (-4535 1125);
FORCEPROP 2 LAST CDS_LIB mstr_discrete
J 0
(-4575 1250);
PAINT MONO (-4575 1250);
DISPLAY INVISIBLE (-4575 1250);
FORCEPROP 2 LAST CDS_LOCATION R7B17
J 0
(-4530 1375);
DISPLAY 0.617021 (-4530 1375);
PAINT AQUA (-4530 1375);
DISPLAY INVISIBLE (-4530 1375);
FORCEPROP 2 LAST ROOM PVPP_KLM_VR
J 0
(-4515 1415);
PAINT GREEN (-4515 1415);
DISPLAY INVISIBLE (-4515 1415);
FORCEPROP 1 LAST PATH I210
J 0
(-4525 1425);
DISPLAY 0.978723 (-4525 1425);
PAINT WHITE (-4525 1425);
DISPLAY INVISIBLE (-4525 1425);
FORCEPROP 2 LAST SEC 1
J 0
(-4525 1475);
DISPLAY 0.680851 (-4525 1475);
PAINT MONO (-4525 1475);
DISPLAY INVISIBLE (-4525 1475);
FORCEPROP 2 LAST BOM_COST PVPP_KLM_VR
J 0
(-4515 1440);
DISPLAY 1.042553 (-4515 1440);
PAINT WHITE (-4515 1440);
DISPLAY INVISIBLE (-4515 1440);
FORCEPROP 2 LAST SEC_TYPE 0402
J 0
(-4525 1475);
DISPLAY 1.042553 (-4525 1475);
PAINT ORANGE (-4525 1475);
DISPLAY INVISIBLE (-4525 1475);
FORCEPROP 2 LAST REUSE_ID 21
J 0
(-4525 1475);
DISPLAY 1.042553 (-4525 1475);
PAINT ORANGE (-4525 1475);
DISPLAY INVISIBLE (-4525 1475);
FORCEADD P3V3_STBY..1
(-4575 1525);
FORCEPROP 3 LASTPIN (-4575 1475) SIG_NAME P3V3_STBY\g
J 0
(-4565 1485);
DISPLAY 0.659574 (-4565 1485);
PAINT MONO (-4565 1485);
DISPLAY INVISIBLE (-4565 1485);
FORCEPROP 1 LAST HDL_POWER P3V3_STBY
J 0
(-4875 1400);
DISPLAY 0.872340 (-4875 1400);
PAINT ORANGE (-4875 1400);
DISPLAY INVISIBLE (-4875 1400);
FORCEPROP 1 LAST BODY_TYPE PLUMBING
J 0
(-4620 1482);
DISPLAY 0.340426 (-4620 1482);
PAINT GREEN (-4620 1482);
DISPLAY INVISIBLE (-4620 1482);
FORCEPROP 1 LAST PATH I211
J 0
(-4530 1527);
DISPLAY 0.340426 (-4530 1527);
PAINT GREEN (-4530 1527);
DISPLAY INVISIBLE (-4530 1527);
FORCEPROP 2 LAST CDS_LIB mstr_symbols
J 0
(-4575 1525);
PAINT MONO (-4575 1525);
DISPLAY INVISIBLE (-4575 1525);
FORCEPROP 1 LAST SIZE 1B
J 0
(-4530 1547);
DISPLAY 0.340426 (-4530 1547);
PAINT GREEN (-4530 1547);
DISPLAY INVISIBLE (-4530 1547);
FORCEPROP 1 LAST VOLTAGE +3.3V
J 0
(-4375 1675);
DISPLAY 1.021277 (-4375 1675);
PAINT SKYBLUE (-4375 1675);
DISPLAY INVISIBLE (-4375 1675);
FORCEADD OFFPAGE..2
(-2900 975);
FORCEPROP 2 LAST $XR0 190 
J 0
(-2711 975);
DISPLAY 0.638298 (-2711 975);
PAINT MONO (-2711 975);
FORCEPROP 2 LAST BOM_COST PVPP_KLM_VR
J 0
(-3600 1050);
DISPLAY 1.042553 (-3600 1050);
PAINT WHITE (-3600 1050);
DISPLAY INVISIBLE (-3600 1050);
FORCEPROP 2 LAST ROOM PVPP_KLM_VR
J 0
(-3325 1050);
DISPLAY 1.042553 (-3325 1050);
PAINT GREEN (-3325 1050);
DISPLAY INVISIBLE (-3325 1050);
FORCEPROP 1 LAST COMMENT_BODY TRUE
J 0
(-2945 880);
DISPLAY 0.872340 (-2945 880);
PAINT PEACH (-2945 880);
DISPLAY INVISIBLE (-2945 880);
FORCEPROP 2 LAST CDS_LIB mstr_standard
J 2
(-2900 975);
PAINT MONO (-2900 975);
DISPLAY INVISIBLE (-2900 975);
FORCEPROP 1 LAST OFFPAGE TRUE
J 0
(-2575 850);
PAINT GREEN (-2575 850);
DISPLAY INVISIBLE (-2575 850);
FORCEPROP 0 LAST TOLERANCE 1%
J 0
(-2725 1050);
PAINT SKYBLUE (-2725 1050);
DISPLAY INVISIBLE (-2725 1050);
FORCEPROP 2 LAST PATH I212
J 0
(-2600 1025);
DISPLAY 1.021277 (-2600 1025);
PAINT ORANGE (-2600 1025);
DISPLAY INVISIBLE (-2600 1025);
FORCEADD NCP3232L..1
(-4150 2875);
FORCEPROP 1 LAST PART_NUMBER H86355-001
J 0
(-4600 1875);
DISPLAY 0.617021 (-4600 1875);
PAINT BLUE (-4600 1875);
FORCEPROP 2 LASTPIN (-4650 2025) $PN 5
J 2
(-4660 2035);
DISPLAY 0.617021 (-4660 2035);
PAINT ORANGE (-4660 2035);
FORCEPROP 2 LASTPIN (-4650 2525) $PN 7
J 2
(-4660 2535);
DISPLAY 0.617021 (-4660 2535);
PAINT ORANGE (-4660 2535);
FORCEPROP 2 LASTPIN (-4650 2825) $PN 40
J 2
(-4660 2835);
DISPLAY 0.617021 (-4660 2835);
PAINT ORANGE (-4660 2835);
FORCEPROP 2 LASTPIN (-4650 2625) $PN 4
J 2
(-4660 2635);
DISPLAY 0.617021 (-4660 2635);
PAINT ORANGE (-4660 2635);
FORCEPROP 2 LASTPIN (-4650 2925) $PN 6
J 2
(-4660 2935);
DISPLAY 0.617021 (-4660 2935);
PAINT ORANGE (-4660 2935);
FORCEPROP 2 LASTPIN (-4650 2725) $PN 1
J 2
(-4660 2735);
DISPLAY 0.617021 (-4660 2735);
PAINT ORANGE (-4660 2735);
FORCEPROP 2 LASTPIN (-4650 3025) $PN 38
J 2
(-4660 3035);
DISPLAY 0.617021 (-4660 3035);
PAINT ORANGE (-4660 3035);
FORCEPROP 2 LASTPIN (-4650 3275) $PN 11
J 2
(-4660 3285);
DISPLAY 0.617021 (-4660 3285);
PAINT ORANGE (-4660 3285);
FORCEPROP 2 LASTPIN (-4650 3225) $PN 10
J 2
(-4660 3235);
DISPLAY 0.617021 (-4660 3235);
PAINT ORANGE (-4660 3235);
FORCEPROP 2 LASTPIN (-4650 3175) $PN 9
J 2
(-4660 3185);
DISPLAY 0.617021 (-4660 3185);
PAINT ORANGE (-4660 3185);
FORCEPROP 2 LASTPIN (-4650 3125) $PN 8
J 2
(-4660 3135);
DISPLAY 0.617021 (-4660 3135);
PAINT ORANGE (-4660 3135);
FORCEPROP 2 LASTPIN (-4650 3475) $PN 42
J 2
(-4660 3485);
DISPLAY 0.617021 (-4660 3485);
PAINT ORANGE (-4660 3485);
FORCEPROP 2 LASTPIN (-4650 3425) $PN 14
J 2
(-4660 3435);
DISPLAY 0.617021 (-4660 3435);
PAINT ORANGE (-4660 3435);
FORCEPROP 2 LASTPIN (-4650 3375) $PN 13
J 2
(-4660 3385);
DISPLAY 0.617021 (-4660 3385);
PAINT ORANGE (-4660 3385);
FORCEPROP 2 LASTPIN (-4650 3325) $PN 12
J 2
(-4660 3335);
DISPLAY 0.617021 (-4660 3335);
PAINT ORANGE (-4660 3335);
FORCEPROP 2 LASTPIN (-4650 3575) $PN 39
J 2
(-4660 3585);
DISPLAY 0.617021 (-4660 3585);
PAINT ORANGE (-4660 3585);
FORCEPROP 1 LAST LOCATION EU7B1
J 0
(-4600 3825);
DISPLAY 0.617021 (-4600 3825);
PAINT AQUA (-4600 3825);
FORCEPROP 1 LAST MATERIAL IC
J 0
(-4600 3775);
DISPLAY 0.617021 (-4600 3775);
PAINT SKYBLUE (-4600 3775);
FORCEPROP 2 LASTPIN (-3650 2025) $PN 41
J 0
(-3640 2035);
DISPLAY 0.617021 (-3640 2035);
PAINT ORANGE (-3640 2035);
FORCEPROP 2 LASTPIN (-3650 2825) $PN 3
J 0
(-3640 2835);
DISPLAY 0.617021 (-3640 2835);
PAINT ORANGE (-3640 2835);
FORCEPROP 2 LASTPIN (-3650 2925) $PN 2
J 0
(-3640 2935);
DISPLAY 0.617021 (-3640 2935);
PAINT ORANGE (-3640 2935);
FORCEPROP 2 LASTPIN (-3650 2075) $PN 16
J 0
(-3640 2085);
DISPLAY 0.617021 (-3640 2085);
PAINT ORANGE (-3640 2085);
FORCEPROP 2 LASTPIN (-3650 2125) $PN 17
J 0
(-3640 2135);
DISPLAY 0.617021 (-3640 2135);
PAINT ORANGE (-3640 2135);
FORCEPROP 2 LASTPIN (-3650 2175) $PN 18
J 0
(-3640 2185);
DISPLAY 0.617021 (-3640 2185);
PAINT ORANGE (-3640 2185);
FORCEPROP 2 LASTPIN (-3650 2225) $PN 19
J 0
(-3640 2235);
DISPLAY 0.617021 (-3640 2235);
PAINT ORANGE (-3640 2235);
FORCEPROP 2 LASTPIN (-3650 2275) $PN 20
J 0
(-3640 2285);
DISPLAY 0.617021 (-3640 2285);
PAINT ORANGE (-3640 2285);
FORCEPROP 2 LASTPIN (-3650 2325) $PN 21
J 0
(-3640 2335);
DISPLAY 0.617021 (-3640 2335);
PAINT ORANGE (-3640 2335);
FORCEPROP 2 LASTPIN (-3650 2375) $PN 22
J 0
(-3640 2385);
DISPLAY 0.617021 (-3640 2385);
PAINT ORANGE (-3640 2385);
FORCEPROP 2 LASTPIN (-3650 2425) $PN 23
J 0
(-3640 2435);
DISPLAY 0.617021 (-3640 2435);
PAINT ORANGE (-3640 2435);
FORCEPROP 2 LASTPIN (-3650 2475) $PN 24
J 0
(-3640 2485);
DISPLAY 0.617021 (-3640 2485);
PAINT ORANGE (-3640 2485);
FORCEPROP 2 LASTPIN (-3650 2525) $PN 25
J 0
(-3640 2535);
DISPLAY 0.617021 (-3640 2535);
PAINT ORANGE (-3640 2535);
FORCEPROP 2 LASTPIN (-3650 2575) $PN 26
J 0
(-3640 2585);
DISPLAY 0.617021 (-3640 2585);
PAINT ORANGE (-3640 2585);
FORCEPROP 2 LASTPIN (-3650 2625) $PN 27
J 0
(-3640 2635);
DISPLAY 0.617021 (-3640 2635);
PAINT ORANGE (-3640 2635);
FORCEPROP 2 LASTPIN (-3650 2675) $PN 28
J 0
(-3640 2685);
DISPLAY 0.617021 (-3640 2685);
PAINT ORANGE (-3640 2685);
FORCEPROP 2 LASTPIN (-3650 2725) $PN 37
J 0
(-3640 2735);
DISPLAY 0.617021 (-3640 2735);
PAINT ORANGE (-3640 2735);
FORCEPROP 2 LASTPIN (-3650 3025) $PN 35
J 0
(-3640 3035);
DISPLAY 0.617021 (-3640 3035);
PAINT ORANGE (-3640 3035);
FORCEPROP 2 LASTPIN (-3650 3575) $PN 36
J 0
(-3640 3585);
DISPLAY 0.617021 (-3640 3585);
PAINT ORANGE (-3640 3585);
FORCEPROP 2 LASTPIN (-3650 3125) $PN 15
J 0
(-3640 3135);
DISPLAY 0.617021 (-3640 3135);
PAINT ORANGE (-3640 3135);
FORCEPROP 2 LASTPIN (-3650 3175) $PN 29
J 0
(-3640 3185);
DISPLAY 0.617021 (-3640 3185);
PAINT ORANGE (-3640 3185);
FORCEPROP 2 LASTPIN (-3650 3225) $PN 30
J 0
(-3640 3235);
DISPLAY 0.617021 (-3640 3235);
PAINT ORANGE (-3640 3235);
FORCEPROP 2 LASTPIN (-3650 3275) $PN 31
J 0
(-3640 3285);
DISPLAY 0.617021 (-3640 3285);
PAINT ORANGE (-3640 3285);
FORCEPROP 2 LASTPIN (-3650 3325) $PN 32
J 0
(-3640 3335);
DISPLAY 0.617021 (-3640 3335);
PAINT ORANGE (-3640 3335);
FORCEPROP 2 LASTPIN (-3650 3375) $PN 33
J 0
(-3640 3385);
DISPLAY 0.617021 (-3640 3385);
PAINT ORANGE (-3640 3385);
FORCEPROP 2 LASTPIN (-3650 3425) $PN 34
J 0
(-3640 3435);
DISPLAY 0.617021 (-3640 3435);
PAINT ORANGE (-3640 3435);
FORCEPROP 2 LASTPIN (-3650 3475) $PN 43
J 0
(-3640 3485);
DISPLAY 0.617021 (-3640 3485);
PAINT ORANGE (-3640 3485);
FORCEPROP 2 LAST CDS_LIB mstr_vreg
J 0
(-4150 2875);
PAINT ORANGE (-4150 2875);
DISPLAY INVISIBLE (-4150 2875);
FORCEPROP 1 LAST CDS_LMAN_SYM_OUTLINE -450,850,450,-900
J 0
(-4150 2875);
DISPLAY 0.468085 (-4150 2875);
PAINT GREEN (-4150 2875);
DISPLAY INVISIBLE (-4150 2875);
FORCEPROP 1 LAST PACK_TYPE SM
J 0
(-4600 3875);
PAINT SKYBLUE (-4600 3875);
DISPLAY INVISIBLE (-4600 3875);
FORCEPROP 2 LAST SEC_TYPE SM
J 0
(-4600 3875);
DISPLAY 1.021277 (-4600 3875);
PAINT ORANGE (-4600 3875);
DISPLAY INVISIBLE (-4600 3875);
FORCEPROP 2 LAST SEC 1
J 0
(-4600 3875);
DISPLAY 0.680851 (-4600 3875);
PAINT MONO (-4600 3875);
DISPLAY INVISIBLE (-4600 3875);
FORCEPROP 2 LAST CDS_LOCATION EU7B1
J 0
(-4600 3825);
DISPLAY 0.617021 (-4600 3825);
PAINT AQUA (-4600 3825);
DISPLAY INVISIBLE (-4600 3825);
FORCEPROP 1 LAST PATH I214
J 0
(-4100 3775);
PAINT GREEN (-4100 3775);
DISPLAY INVISIBLE (-4100 3775);
FORCEADD GND..1
(-3425 1925);
FORCEPROP 3 LASTPIN (-3425 1975) SIG_NAME GND\g
J 0
(-3415 1985);
DISPLAY 0.659574 (-3415 1985);
PAINT MONO (-3415 1985);
DISPLAY INVISIBLE (-3415 1985);
FORCEPROP 2 LAST BOM_COST PVPP_KLM_VR
J 0
(-4325 2075);
DISPLAY 1.042553 (-4325 2075);
PAINT WHITE (-4325 2075);
DISPLAY INVISIBLE (-4325 2075);
FORCEPROP 1 LAST BODY_TYPE PLUMBING
J 0
(-3470 1882);
DISPLAY 0.340426 (-3470 1882);
PAINT GREEN (-3470 1882);
DISPLAY INVISIBLE (-3470 1882);
FORCEPROP 2 LAST CDS_LIB mstr_symbols
J 0
(-3425 1925);
PAINT MONO (-3425 1925);
DISPLAY INVISIBLE (-3425 1925);
FORCEPROP 1 LAST VOLTAGE 0
J 0
(-3425 2000);
PAINT SKYBLUE (-3425 2000);
DISPLAY INVISIBLE (-3425 2000);
FORCEPROP 1 LAST PATH I215
J 0
(-3350 1925);
DISPLAY 0.872340 (-3350 1925);
PAINT AQUA (-3350 1925);
DISPLAY INVISIBLE (-3350 1925);
FORCEPROP 1 LAST SIZE 1B
J 0
(-3350 1950);
DISPLAY 0.893617 (-3350 1950);
PAINT GREEN (-3350 1950);
DISPLAY INVISIBLE (-3350 1950);
FORCEPROP 2 LAST ROOM PVPP_KLM_VR
J 0
(-4075 2075);
PAINT GREEN (-4075 2075);
DISPLAY INVISIBLE (-4075 2075);
FORCEPROP 1 LAST HDL_POWER GND
J 0
(-3425 2150);
DISPLAY 0.893617 (-3425 2150);
PAINT GREEN (-3425 2150);
DISPLAY INVISIBLE (-3425 2150);
FORCEADD RES..2
(-3000 3350);
FORCEPROP 1 LASTPIN (-3000 3250) $PN 2
J 0
(-2995 3260);
DISPLAY 0.617021 (-2995 3260);
PAINT WHITE (-2995 3260);
FORCEPROP 1 LASTPIN (-3000 3450) $PN 1
J 0
(-2995 3412);
DISPLAY 0.617021 (-2995 3412);
PAINT WHITE (-2995 3412);
FORCEPROP 1 LAST TOLERANCE 5%
J 0
(-2880 3375);
DISPLAY 0.617021 (-2880 3375);
PAINT SKYBLUE (-2880 3375);
FORCEPROP 1 LAST WATTAGE 1/16W
J 0
(-2885 3275);
DISPLAY 0.617021 (-2885 3275);
PAINT SKYBLUE (-2885 3275);
FORCEPROP 1 LAST PACK_TYPE 0402
J 0
(-2885 3225);
DISPLAY 0.617021 (-2885 3225);
PAINT SKYBLUE (-2885 3225);
FORCEPROP 1 LAST VALUE 2.2
J 0
(-2880 3425);
DISPLAY 0.617021 (-2880 3425);
PAINT SKYBLUE (-2880 3425);
FORCEPROP 1 LAST PART_NUMBER G21497-016
J 0
(-2885 3175);
DISPLAY 0.617021 (-2885 3175);
PAINT BLUE (-2885 3175);
FORCEPROP 1 LAST LOCATION R7A15
J 0
(-2955 3450);
DISPLAY 0.617021 (-2955 3450);
PAINT AQUA (-2955 3450);
FORCEPROP 1 LAST MATERIAL EMPTY
J 0
(-2885 3325);
DISPLAY 0.617021 (-2885 3325);
PAINT RED (-2885 3325);
FORCEPROP 2 LAST CDS_LIB mstr_discrete
J 0
(-3000 3350);
PAINT MONO (-3000 3350);
DISPLAY INVISIBLE (-3000 3350);
FORCEPROP 2 LAST CDS_LOCATION R7A15
J 0
(-2955 3450);
DISPLAY 0.617021 (-2955 3450);
PAINT AQUA (-2955 3450);
DISPLAY INVISIBLE (-2955 3450);
FORCEPROP 2 LAST ROOM PVPP_KLM_VR
J 0
(-2950 3500);
PAINT GREEN (-2950 3500);
DISPLAY INVISIBLE (-2950 3500);
FORCEPROP 1 LAST PATH I218
J 0
(-2950 3525);
DISPLAY 0.978723 (-2950 3525);
PAINT WHITE (-2950 3525);
DISPLAY INVISIBLE (-2950 3525);
FORCEPROP 2 LAST BOM_COST PVPP_KLM_VR
J 0
(-2950 3525);
DISPLAY 1.042553 (-2950 3525);
PAINT WHITE (-2950 3525);
DISPLAY INVISIBLE (-2950 3525);
FORCEPROP 2 LAST SEC 1
J 0
(-2950 3575);
DISPLAY 0.680851 (-2950 3575);
PAINT MONO (-2950 3575);
DISPLAY INVISIBLE (-2950 3575);
FORCEPROP 2 LAST REUSE_ID 29
J 0
(-2950 3575);
DISPLAY 1.042553 (-2950 3575);
PAINT ORANGE (-2950 3575);
DISPLAY INVISIBLE (-2950 3575);
FORCEPROP 2 LAST SEC_TYPE 0402
J 0
(-2950 3575);
DISPLAY 1.021277 (-2950 3575);
PAINT ORANGE (-2950 3575);
DISPLAY INVISIBLE (-2950 3575);
FORCEADD GND..1
(-3000 3150);
FORCEPROP 3 LASTPIN (-3000 3200) SIG_NAME GND\g
J 0
(-2990 3210);
DISPLAY 0.659574 (-2990 3210);
PAINT MONO (-2990 3210);
DISPLAY INVISIBLE (-2990 3210);
FORCEPROP 2 LAST BOM_COST PVPP_KLM_VR
J 0
(-3900 3300);
DISPLAY 1.042553 (-3900 3300);
PAINT WHITE (-3900 3300);
DISPLAY INVISIBLE (-3900 3300);
FORCEPROP 2 LAST ROOM PVPP_KLM_VR
J 0
(-3650 3300);
PAINT GREEN (-3650 3300);
DISPLAY INVISIBLE (-3650 3300);
FORCEPROP 1 LAST BODY_TYPE PLUMBING
J 0
(-3045 3107);
DISPLAY 0.340426 (-3045 3107);
PAINT GREEN (-3045 3107);
DISPLAY INVISIBLE (-3045 3107);
FORCEPROP 2 LAST CDS_LIB mstr_symbols
J 0
(-3000 3225);
PAINT MONO (-3000 3225);
DISPLAY INVISIBLE (-3000 3225);
FORCEPROP 1 LAST VOLTAGE 0
J 0
(-3000 3225);
PAINT SKYBLUE (-3000 3225);
DISPLAY INVISIBLE (-3000 3225);
FORCEPROP 1 LAST PATH I219
J 0
(-2925 3150);
DISPLAY 0.872340 (-2925 3150);
PAINT AQUA (-2925 3150);
DISPLAY INVISIBLE (-2925 3150);
FORCEPROP 1 LAST SIZE 1B
J 0
(-2925 3175);
DISPLAY 0.893617 (-2925 3175);
PAINT GREEN (-2925 3175);
DISPLAY INVISIBLE (-2925 3175);
FORCEPROP 1 LAST HDL_POWER GND
J 0
(-3000 3375);
DISPLAY 0.893617 (-3000 3375);
PAINT GREEN (-3000 3375);
DISPLAY INVISIBLE (-3000 3375);
FORCEADD CAP..1
(-3000 3700);
FORCEPROP 1 LAST PART_NUMBER A36096-091
J 0
(-2875 3550);
DISPLAY 0.617021 (-2875 3550);
PAINT BLUE (-2875 3550);
FORCEPROP 1 LASTPIN (-3000 3600) $PN 2
J 0
(-2990 3580);
DISPLAY 0.617021 (-2990 3580);
PAINT WHITE (-2990 3580);
FORCEPROP 1 LASTPIN (-3000 3800) $PN 1
J 0
(-2990 3780);
DISPLAY 0.617021 (-2990 3780);
PAINT WHITE (-2990 3780);
FORCEPROP 1 LAST VOLTAGE 50V
J 0
(-2875 3700);
DISPLAY 0.617021 (-2875 3700);
PAINT SKYBLUE (-2875 3700);
FORCEPROP 1 LAST PACK_TYPE 0402LF
J 0
(-2875 3600);
DISPLAY 0.617021 (-2875 3600);
PAINT SKYBLUE (-2875 3600);
FORCEPROP 1 LAST TOLERANCE 10%
J 0
(-2875 3650);
DISPLAY 0.617021 (-2875 3650);
PAINT SKYBLUE (-2875 3650);
FORCEPROP 1 LAST VALUE 3300PF
J 0
(-2875 3750);
DISPLAY 0.617021 (-2875 3750);
PAINT SKYBLUE (-2875 3750);
FORCEPROP 1 LAST LOCATION C7A34
J 0
(-2900 3800);
DISPLAY 0.617021 (-2900 3800);
PAINT AQUA (-2900 3800);
FORCEPROP 1 LAST MATERIAL EMPTY
J 0
(-2775 3675);
DISPLAY 0.617021 (-2775 3675);
PAINT RED (-2775 3675);
FORCEPROP 2 LAST CDS_LIB mstr_discrete
J 0
(-3000 3700);
PAINT MONO (-3000 3700);
DISPLAY INVISIBLE (-3000 3700);
FORCEPROP 2 LAST CDS_LOCATION C7A34
J 0
(-2900 3800);
DISPLAY 0.617021 (-2900 3800);
PAINT AQUA (-2900 3800);
DISPLAY INVISIBLE (-2900 3800);
FORCEPROP 2 LAST ROOM PVPP_KLM_VR
J 0
(-2950 3825);
PAINT GREEN (-2950 3825);
DISPLAY INVISIBLE (-2950 3825);
FORCEPROP 1 LAST PATH I220
J 0
(-2950 3850);
DISPLAY 0.978723 (-2950 3850);
PAINT WHITE (-2950 3850);
DISPLAY INVISIBLE (-2950 3850);
FORCEPROP 2 LAST SEC 1
J 0
(-2950 3900);
DISPLAY 0.680851 (-2950 3900);
PAINT MONO (-2950 3900);
DISPLAY INVISIBLE (-2950 3900);
FORCEPROP 2 LAST BOM_COST PVPP_KLM_VR
J 0
(-2950 3850);
DISPLAY 1.042553 (-2950 3850);
PAINT WHITE (-2950 3850);
DISPLAY INVISIBLE (-2950 3850);
FORCEPROP 2 LAST REUSE_ID 26
J 0
(-2950 3900);
DISPLAY 1.042553 (-2950 3900);
PAINT ORANGE (-2950 3900);
DISPLAY INVISIBLE (-2950 3900);
FORCEPROP 2 LAST SEC_TYPE 0402LF
J 0
(-2950 3900);
DISPLAY 1.021277 (-2950 3900);
PAINT ORANGE (-2950 3900);
DISPLAY INVISIBLE (-2950 3900);
FORCEADD GND..1
(-2425 3425);
FORCEPROP 3 LASTPIN (-2425 3475) SIG_NAME GND\g
J 0
(-2415 3485);
DISPLAY 0.659574 (-2415 3485);
PAINT MONO (-2415 3485);
DISPLAY INVISIBLE (-2415 3485);
FORCEPROP 2 LAST BOM_COST PVPP_KLM_VR
J 0
(-3275 3500);
DISPLAY 1.042553 (-3275 3500);
PAINT WHITE (-3275 3500);
DISPLAY INVISIBLE (-3275 3500);
FORCEPROP 2 LAST ROOM PVPP_KLM_VR
J 0
(-3000 3500);
DISPLAY 1.042553 (-3000 3500);
PAINT GREEN (-3000 3500);
DISPLAY INVISIBLE (-3000 3500);
FORCEPROP 1 LAST BODY_TYPE PLUMBING
J 0
(-2470 3382);
DISPLAY 0.340426 (-2470 3382);
PAINT GREEN (-2470 3382);
DISPLAY INVISIBLE (-2470 3382);
FORCEPROP 1 LAST PATH I226
J 0
(-2350 3425);
DISPLAY 0.872340 (-2350 3425);
PAINT AQUA (-2350 3425);
DISPLAY INVISIBLE (-2350 3425);
FORCEPROP 1 LAST SIZE 1B
J 0
(-2350 3375);
DISPLAY 0.872340 (-2350 3375);
PAINT GREEN (-2350 3375);
DISPLAY INVISIBLE (-2350 3375);
FORCEPROP 2 LAST CDS_LIB mstr_symbols
J 0
(-2425 3425);
PAINT MONO (-2425 3425);
DISPLAY INVISIBLE (-2425 3425);
FORCEPROP 1 LAST VOLTAGE 0
J 0
(-2425 3425);
PAINT SKYBLUE (-2425 3425);
DISPLAY INVISIBLE (-2425 3425);
FORCEPROP 1 LAST HDL_POWER GND
J 0
(-2425 3575);
DISPLAY 0.872340 (-2425 3575);
PAINT GREEN (-2425 3575);
DISPLAY INVISIBLE (-2425 3575);
FORCEADD RES..2
(-2425 3675);
FORCEPROP 1 LAST PACK_TYPE 0603
J 0
(-2385 3500);
DISPLAY 0.617021 (-2385 3500);
PAINT SKYBLUE (-2385 3500);
FORCEPROP 1 LAST PART_NUMBER G22026-003
J 0
(-2385 3550);
DISPLAY 0.617021 (-2385 3550);
PAINT BLUE (-2385 3550);
FORCEPROP 1 LASTPIN (-2425 3775) $PN 1
J 0
(-2420 3737);
DISPLAY 0.617021 (-2420 3737);
PAINT WHITE (-2420 3737);
FORCEPROP 1 LASTPIN (-2425 3575) $PN 2
J 0
(-2420 3585);
DISPLAY 0.617021 (-2420 3585);
PAINT WHITE (-2420 3585);
FORCEPROP 1 LAST TOLERANCE 1%
J 0
(-2380 3700);
DISPLAY 0.617021 (-2380 3700);
PAINT SKYBLUE (-2380 3700);
FORCEPROP 1 LAST WATTAGE 1/10W
J 0
(-2385 3650);
DISPLAY 0.617021 (-2385 3650);
PAINT SKYBLUE (-2385 3650);
FORCEPROP 1 LAST MATERIAL CHIP
J 0
(-2385 3600);
DISPLAY 0.617021 (-2385 3600);
PAINT SKYBLUE (-2385 3600);
FORCEPROP 1 LAST VALUE 120.0
J 0
(-2380 3750);
DISPLAY 0.617021 (-2380 3750);
PAINT SKYBLUE (-2380 3750);
FORCEPROP 1 LAST LOCATION R7B10
J 0
(-2380 3800);
DISPLAY 0.617021 (-2380 3800);
PAINT AQUA (-2380 3800);
FORCEPROP 2 LAST CDS_LOCATION R7B10
J 0
(-2380 3800);
DISPLAY 0.617021 (-2380 3800);
PAINT AQUA (-2380 3800);
DISPLAY INVISIBLE (-2380 3800);
FORCEPROP 2 LAST CDS_LIB mstr_discrete
J 0
(-2425 3675);
PAINT MONO (-2425 3675);
DISPLAY INVISIBLE (-2425 3675);
FORCEPROP 2 LAST ROOM PVPP_KLM_VR
J 0
(-2380 3830);
PAINT GREEN (-2380 3830);
DISPLAY INVISIBLE (-2380 3830);
FORCEPROP 2 LAST SEC_TYPE 0603
J 0
(-2375 3900);
DISPLAY 1.021277 (-2375 3900);
PAINT ORANGE (-2375 3900);
DISPLAY INVISIBLE (-2375 3900);
FORCEPROP 2 LAST SEC 1
J 0
(-2375 3900);
DISPLAY 0.680851 (-2375 3900);
PAINT MONO (-2375 3900);
DISPLAY INVISIBLE (-2375 3900);
FORCEPROP 2 LAST REUSE_ID 34
J 0
(-2375 3900);
DISPLAY 1.042553 (-2375 3900);
PAINT ORANGE (-2375 3900);
DISPLAY INVISIBLE (-2375 3900);
FORCEPROP 2 LAST BOM_COST PVPP_KLM_VR
J 0
(-2380 3855);
DISPLAY 1.042553 (-2380 3855);
PAINT WHITE (-2380 3855);
DISPLAY INVISIBLE (-2380 3855);
FORCEPROP 1 LAST PATH I227
J 0
(-2375 3850);
DISPLAY 0.978723 (-2375 3850);
PAINT WHITE (-2375 3850);
DISPLAY INVISIBLE (-2375 3850);
FORCEADD GND..1
(-2075 3375);
FORCEPROP 3 LASTPIN (-2075 3425) SIG_NAME GND\g
J 0
(-2065 3435);
DISPLAY 0.659574 (-2065 3435);
PAINT MONO (-2065 3435);
DISPLAY INVISIBLE (-2065 3435);
FORCEPROP 2 LAST BOM_COST PVPP_KLM_VR
J 0
(-2925 3450);
DISPLAY 1.042553 (-2925 3450);
PAINT WHITE (-2925 3450);
DISPLAY INVISIBLE (-2925 3450);
FORCEPROP 2 LAST ROOM PVPP_KLM_VR
J 0
(-2650 3450);
DISPLAY 1.042553 (-2650 3450);
PAINT GREEN (-2650 3450);
DISPLAY INVISIBLE (-2650 3450);
FORCEPROP 2 LAST CDS_LIB mstr_symbols
J 0
(-2075 3375);
PAINT MONO (-2075 3375);
DISPLAY INVISIBLE (-2075 3375);
FORCEPROP 1 LAST VOLTAGE 0
J 0
(-2075 3375);
PAINT SKYBLUE (-2075 3375);
DISPLAY INVISIBLE (-2075 3375);
FORCEPROP 1 LAST BODY_TYPE PLUMBING
J 0
(-2120 3332);
DISPLAY 0.340426 (-2120 3332);
PAINT GREEN (-2120 3332);
DISPLAY INVISIBLE (-2120 3332);
FORCEPROP 1 LAST HDL_POWER GND
J 0
(-2075 3525);
DISPLAY 0.872340 (-2075 3525);
PAINT GREEN (-2075 3525);
DISPLAY INVISIBLE (-2075 3525);
FORCEPROP 1 LAST SIZE 1B
J 0
(-2000 3325);
DISPLAY 0.872340 (-2000 3325);
PAINT GREEN (-2000 3325);
DISPLAY INVISIBLE (-2000 3325);
FORCEPROP 1 LAST PATH I228
J 0
(-2000 3375);
DISPLAY 0.872340 (-2000 3375);
PAINT AQUA (-2000 3375);
DISPLAY INVISIBLE (-2000 3375);
FORCEADD CAPP..1
(-2075 3675);
FORCEPROP 1 LASTPIN (-2075 3775) $PN 1
J 0
(-2065 3760);
DISPLAY 0.617021 (-2065 3760);
PAINT WHITE (-2065 3760);
FORCEPROP 1 LASTPIN (-2075 3575) $PN 2
J 0
(-2065 3560);
DISPLAY 0.617021 (-2065 3560);
PAINT WHITE (-2065 3560);
FORCEPROP 1 LAST PART_NUMBER 724613-042
J 0
(-2050 3475);
DISPLAY 0.617021 (-2050 3475);
PAINT BLUE (-2050 3475);
FORCEPROP 1 LAST PACK_TYPE 7343LF
J 0
(-2025 3525);
DISPLAY 0.617021 (-2025 3525);
PAINT SKYBLUE (-2025 3525);
FORCEPROP 1 LAST MATERIAL POSCAP
J 0
(-2025 3575);
DISPLAY 0.617021 (-2025 3575);
PAINT SKYBLUE (-2025 3575);
FORCEPROP 1 LAST TOLERANCE 20%
J 0
(-2025 3675);
DISPLAY 0.617021 (-2025 3675);
PAINT SKYBLUE (-2025 3675);
FORCEPROP 1 LAST VOLTAGE 6.3V
J 0
(-2025 3625);
DISPLAY 0.617021 (-2025 3625);
PAINT SKYBLUE (-2025 3625);
FORCEPROP 1 LAST VALUE 330UF
J 0
(-2025 3725);
DISPLAY 0.617021 (-2025 3725);
PAINT SKYBLUE (-2025 3725);
FORCEPROP 1 LAST LOCATION C6B7
J 0
(-2025 3775);
DISPLAY 0.617021 (-2025 3775);
PAINT AQUA (-2025 3775);
FORCEPROP 2 LAST BOM_COST PVPP_KLM_VR
J 0
(-2075 3675);
DISPLAY 0.659574 (-2075 3675);
PAINT WHITE (-2075 3675);
DISPLAY INVISIBLE (-2075 3675);
FORCEPROP 2 LAST ROOM PVPP_KLM_VR
J 0
(-2075 3675);
PAINT GREEN (-2075 3675);
DISPLAY INVISIBLE (-2075 3675);
FORCEPROP 2 LAST CDS_LIB mstr_discrete
J 0
(-2075 3675);
PAINT MONO (-2075 3675);
DISPLAY INVISIBLE (-2075 3675);
FORCEPROP 2 LAST CDS_LOCATION C6B7
J 0
(-2025 3775);
DISPLAY 0.617021 (-2025 3775);
PAINT AQUA (-2025 3775);
DISPLAY INVISIBLE (-2025 3775);
FORCEPROP 1 LAST PATH I229
J 0
(-2025 3825);
DISPLAY 0.978723 (-2025 3825);
PAINT ORANGE (-2025 3825);
DISPLAY INVISIBLE (-2025 3825);
FORCEPROP 2 LAST $SEC 1
J 0
(-2025 3875);
DISPLAY 0.680851 (-2025 3875);
PAINT MONO (-2025 3875);
DISPLAY INVISIBLE (-2025 3875);
FORCEPROP 2 LAST CDS_SEC 1
J 0
(-2025 3875);
DISPLAY 1.042553 (-2025 3875);
PAINT ORANGE (-2025 3875);
DISPLAY INVISIBLE (-2025 3875);
FORCEPROP 2 LAST REUSE_ID 28
J 0
(-2025 3875);
DISPLAY 1.042553 (-2025 3875);
PAINT ORANGE (-2025 3875);
DISPLAY INVISIBLE (-2025 3875);
FORCEADD GND..1
(-1475 3425);
FORCEPROP 3 LASTPIN (-1475 3475) SIG_NAME GND\g
J 0
(-1465 3485);
DISPLAY 0.659574 (-1465 3485);
PAINT MONO (-1465 3485);
DISPLAY INVISIBLE (-1465 3485);
FORCEPROP 2 LAST BOM_COST PVPP_KLM_VR
J 0
(-2325 3500);
DISPLAY 1.042553 (-2325 3500);
PAINT WHITE (-2325 3500);
DISPLAY INVISIBLE (-2325 3500);
FORCEPROP 2 LAST ROOM PVPP_KLM_VR
J 0
(-2050 3500);
DISPLAY 1.042553 (-2050 3500);
PAINT GREEN (-2050 3500);
DISPLAY INVISIBLE (-2050 3500);
FORCEPROP 1 LAST BODY_TYPE PLUMBING
J 0
(-1520 3382);
DISPLAY 0.340426 (-1520 3382);
PAINT GREEN (-1520 3382);
DISPLAY INVISIBLE (-1520 3382);
FORCEPROP 2 LAST CDS_LIB mstr_symbols
J 0
(-1475 3425);
PAINT MONO (-1475 3425);
DISPLAY INVISIBLE (-1475 3425);
FORCEPROP 1 LAST VOLTAGE 0
J 0
(-1475 3425);
PAINT SKYBLUE (-1475 3425);
DISPLAY INVISIBLE (-1475 3425);
FORCEPROP 1 LAST PATH I235
J 0
(-1400 3425);
DISPLAY 0.872340 (-1400 3425);
PAINT AQUA (-1400 3425);
DISPLAY INVISIBLE (-1400 3425);
FORCEPROP 1 LAST SIZE 1B
J 0
(-1400 3375);
DISPLAY 0.872340 (-1400 3375);
PAINT GREEN (-1400 3375);
DISPLAY INVISIBLE (-1400 3375);
FORCEPROP 1 LAST HDL_POWER GND
J 0
(-1475 3575);
DISPLAY 0.872340 (-1475 3575);
PAINT GREEN (-1475 3575);
DISPLAY INVISIBLE (-1475 3575);
FORCEADD CAP..1
(-1475 3675);
FORCEPROP 1 LASTPIN (-1475 3575) $PN 2
J 0
(-1465 3555);
DISPLAY 0.617021 (-1465 3555);
PAINT WHITE (-1465 3555);
FORCEPROP 1 LAST PACK_TYPE 0805
J 0
(-1425 3475);
DISPLAY 0.617021 (-1425 3475);
PAINT SKYBLUE (-1425 3475);
FORCEPROP 1 LAST PART_NUMBER C95333-006
J 0
(-1425 3525);
DISPLAY 0.617021 (-1425 3525);
PAINT BLUE (-1425 3525);
FORCEPROP 1 LAST MATERIAL X6S
J 0
(-1425 3575);
DISPLAY 0.617021 (-1425 3575);
PAINT SKYBLUE (-1425 3575);
FORCEPROP 1 LASTPIN (-1475 3775) $PN 1
J 0
(-1465 3755);
DISPLAY 0.617021 (-1465 3755);
PAINT WHITE (-1465 3755);
FORCEPROP 1 LAST VOLTAGE 4V
J 0
(-1425 3675);
DISPLAY 0.617021 (-1425 3675);
PAINT SKYBLUE (-1425 3675);
FORCEPROP 1 LAST LOCATION C6B3
J 0
(-1425 3775);
DISPLAY 0.617021 (-1425 3775);
PAINT AQUA (-1425 3775);
FORCEPROP 1 LAST VALUE 47UF
J 0
(-1425 3725);
DISPLAY 0.617021 (-1425 3725);
PAINT SKYBLUE (-1425 3725);
FORCEPROP 1 LAST TOLERANCE 20%
J 0
(-1425 3625);
DISPLAY 0.617021 (-1425 3625);
PAINT SKYBLUE (-1425 3625);
FORCEPROP 2 LAST ROOM PVPP_KLM_VR
J 0
(-1475 3675);
PAINT GREEN (-1475 3675);
DISPLAY INVISIBLE (-1475 3675);
FORCEPROP 2 LAST BOM_COST PVPP_KLM_VR
J 0
(-1475 3675);
PAINT WHITE (-1475 3675);
DISPLAY INVISIBLE (-1475 3675);
FORCEPROP 2 LAST CDS_LIB mstr_discrete
J 0
(-1475 3675);
PAINT MONO (-1475 3675);
DISPLAY INVISIBLE (-1475 3675);
FORCEPROP 2 LAST CDS_LOCATION C6B3
J 0
(-1425 3775);
DISPLAY 0.617021 (-1425 3775);
PAINT AQUA (-1425 3775);
DISPLAY INVISIBLE (-1425 3775);
FORCEPROP 1 LAST PATH I236
J 0
(-1425 3825);
DISPLAY 0.978723 (-1425 3825);
PAINT WHITE (-1425 3825);
DISPLAY INVISIBLE (-1425 3825);
FORCEPROP 2 LAST $SEC 1
J 0
(-1425 3875);
DISPLAY 0.680851 (-1425 3875);
PAINT MONO (-1425 3875);
DISPLAY INVISIBLE (-1425 3875);
FORCEPROP 2 LAST CDS_SEC 1
J 0
(-1425 3875);
DISPLAY 1.042553 (-1425 3875);
PAINT ORANGE (-1425 3875);
DISPLAY INVISIBLE (-1425 3875);
FORCEPROP 2 LAST REUSE_ID 33
J 0
(-1425 3875);
DISPLAY 1.042553 (-1425 3875);
PAINT ORANGE (-1425 3875);
DISPLAY INVISIBLE (-1425 3875);
FORCEADD GND..1
(-1200 3400);
FORCEPROP 3 LASTPIN (-1200 3450) SIG_NAME GND\g
J 0
(-1190 3460);
DISPLAY 0.659574 (-1190 3460);
PAINT MONO (-1190 3460);
DISPLAY INVISIBLE (-1190 3460);
FORCEPROP 2 LAST BOM_COST PVPP_KLM_VR
J 0
(-2050 3475);
DISPLAY 1.042553 (-2050 3475);
PAINT WHITE (-2050 3475);
DISPLAY INVISIBLE (-2050 3475);
FORCEPROP 2 LAST ROOM PVPP_KLM_VR
J 0
(-1775 3475);
DISPLAY 1.042553 (-1775 3475);
PAINT GREEN (-1775 3475);
DISPLAY INVISIBLE (-1775 3475);
FORCEPROP 1 LAST BODY_TYPE PLUMBING
J 0
(-1245 3357);
DISPLAY 0.340426 (-1245 3357);
PAINT GREEN (-1245 3357);
DISPLAY INVISIBLE (-1245 3357);
FORCEPROP 2 LAST CDS_LIB mstr_symbols
J 0
(-1200 3400);
PAINT MONO (-1200 3400);
DISPLAY INVISIBLE (-1200 3400);
FORCEPROP 1 LAST VOLTAGE 0
J 0
(-1200 3400);
PAINT SKYBLUE (-1200 3400);
DISPLAY INVISIBLE (-1200 3400);
FORCEPROP 1 LAST PATH I237
J 0
(-1125 3400);
DISPLAY 0.872340 (-1125 3400);
PAINT AQUA (-1125 3400);
DISPLAY INVISIBLE (-1125 3400);
FORCEPROP 1 LAST SIZE 1B
J 0
(-1125 3350);
DISPLAY 0.872340 (-1125 3350);
PAINT GREEN (-1125 3350);
DISPLAY INVISIBLE (-1125 3350);
FORCEPROP 1 LAST HDL_POWER GND
J 0
(-1200 3550);
DISPLAY 0.872340 (-1200 3550);
PAINT GREEN (-1200 3550);
DISPLAY INVISIBLE (-1200 3550);
FORCEADD CAP..1
(-1200 3675);
FORCEPROP 1 LASTPIN (-1200 3575) $PN 2
J 0
(-1190 3555);
DISPLAY 0.617021 (-1190 3555);
PAINT WHITE (-1190 3555);
FORCEPROP 1 LAST PACK_TYPE 0805
J 0
(-1150 3475);
DISPLAY 0.617021 (-1150 3475);
PAINT SKYBLUE (-1150 3475);
FORCEPROP 1 LAST MATERIAL X6S
J 0
(-1150 3575);
DISPLAY 0.617021 (-1150 3575);
PAINT SKYBLUE (-1150 3575);
FORCEPROP 1 LASTPIN (-1200 3775) $PN 1
J 0
(-1190 3755);
DISPLAY 0.617021 (-1190 3755);
PAINT WHITE (-1190 3755);
FORCEPROP 1 LAST VOLTAGE 4V
J 0
(-1150 3675);
DISPLAY 0.617021 (-1150 3675);
PAINT SKYBLUE (-1150 3675);
FORCEPROP 1 LAST TOLERANCE 20%
J 0
(-1150 3625);
DISPLAY 0.617021 (-1150 3625);
PAINT SKYBLUE (-1150 3625);
FORCEPROP 1 LAST VALUE 47UF
J 0
(-1150 3725);
DISPLAY 0.617021 (-1150 3725);
PAINT SKYBLUE (-1150 3725);
FORCEPROP 1 LAST LOCATION C7B7
J 0
(-1150 3775);
DISPLAY 0.617021 (-1150 3775);
PAINT AQUA (-1150 3775);
FORCEPROP 1 LAST PART_NUMBER C95333-006
J 0
(-1150 3525);
DISPLAY 0.617021 (-1150 3525);
PAINT BLUE (-1150 3525);
FORCEPROP 2 LAST ROOM PVPP_KLM_VR
J 0
(-1200 3675);
PAINT GREEN (-1200 3675);
DISPLAY INVISIBLE (-1200 3675);
FORCEPROP 2 LAST CDS_LOCATION C7B7
J 0
(-1150 3775);
DISPLAY 0.617021 (-1150 3775);
PAINT AQUA (-1150 3775);
DISPLAY INVISIBLE (-1150 3775);
FORCEPROP 2 LAST CDS_LIB mstr_discrete
J 0
(-1200 3675);
PAINT MONO (-1200 3675);
DISPLAY INVISIBLE (-1200 3675);
FORCEPROP 2 LAST BOM_COST PVPP_KLM_VR
J 0
(-1200 3675);
PAINT WHITE (-1200 3675);
DISPLAY INVISIBLE (-1200 3675);
FORCEPROP 1 LAST PATH I238
J 0
(-1150 3825);
DISPLAY 0.978723 (-1150 3825);
PAINT WHITE (-1150 3825);
DISPLAY INVISIBLE (-1150 3825);
FORCEPROP 2 LAST $SEC 1
J 0
(-1150 3875);
DISPLAY 0.680851 (-1150 3875);
PAINT MONO (-1150 3875);
DISPLAY INVISIBLE (-1150 3875);
FORCEPROP 2 LAST CDS_SEC 1
J 0
(-1150 3875);
DISPLAY 1.042553 (-1150 3875);
PAINT ORANGE (-1150 3875);
DISPLAY INVISIBLE (-1150 3875);
FORCEPROP 2 LAST REUSE_ID 33
J 0
(-1150 3875);
DISPLAY 1.042553 (-1150 3875);
PAINT ORANGE (-1150 3875);
DISPLAY INVISIBLE (-1150 3875);
FORCEADD INDUCTOR..1
(-2650 3850);
FORCEPROP 1 LAST VALUE 0.47UH
J 2
(-2780 3865);
DISPLAY 0.617021 (-2780 3865);
PAINT SKYBLUE (-2780 3865);
FORCEPROP 1 LAST MATERIAL IND
J 0
(-2685 3790);
DISPLAY 0.617021 (-2685 3790);
PAINT SKYBLUE (-2685 3790);
FORCEPROP 1 LASTPIN (-2750 3850) $PN 1
J 0
(-2750 3860);
DISPLAY 0.617021 (-2750 3860);
PAINT WHITE (-2750 3860);
FORCEPROP 1 LAST LOCATION L7B1
J 0
(-2700 3900);
DISPLAY 0.617021 (-2700 3900);
PAINT AQUA (-2700 3900);
FORCEPROP 1 LASTPIN (-2550 3850) $PN 2
J 2
(-2540 3860);
DISPLAY 0.617021 (-2540 3860);
PAINT WHITE (-2540 3860);
FORCEPROP 1 LAST PART_NUMBER E13358-018
J 0
(-2750 3950);
DISPLAY 0.617021 (-2750 3950);
PAINT BLUE (-2750 3950);
FORCEPROP 1 LAST PACK_TYPE SM
J 0
(-2510 3865);
DISPLAY 0.617021 (-2510 3865);
PAINT SKYBLUE (-2510 3865);
FORCEPROP 1 LAST PATH I239
J 0
(-2750 4000);
DISPLAY 0.978723 (-2750 4000);
PAINT ORANGE (-2750 4000);
DISPLAY INVISIBLE (-2750 4000);
FORCEPROP 2 LAST CDS_LOCATION L7B1
J 0
(-2700 3900);
DISPLAY 0.617021 (-2700 3900);
PAINT AQUA (-2700 3900);
DISPLAY INVISIBLE (-2700 3900);
FORCEPROP 2 LAST $SEC 1
J 0
(-2750 4050);
DISPLAY 0.680851 (-2750 4050);
PAINT MONO (-2750 4050);
DISPLAY INVISIBLE (-2750 4050);
FORCEPROP 2 LAST CDS_SEC 1
J 0
(-2750 4050);
DISPLAY 1.042553 (-2750 4050);
PAINT ORANGE (-2750 4050);
DISPLAY INVISIBLE (-2750 4050);
FORCEPROP 2 LAST REUSE_ID 30
J 0
(-2750 4050);
DISPLAY 1.042553 (-2750 4050);
PAINT ORANGE (-2750 4050);
DISPLAY INVISIBLE (-2750 4050);
FORCEPROP 0 LAST TOLERANCE 1%
J 0
(-2750 4000);
PAINT SKYBLUE (-2750 4000);
DISPLAY INVISIBLE (-2750 4000);
FORCEPROP 2 LAST ROOM PVPP_KLM_VR
J 2
(-2650 3850);
PAINT GREEN (-2650 3850);
DISPLAY INVISIBLE (-2650 3850);
FORCEPROP 2 LAST BOM_COST PVPP_KLM_VR
J 0
(-2650 3850);
PAINT WHITE (-2650 3850);
DISPLAY INVISIBLE (-2650 3850);
FORCEPROP 2 LAST CDS_LIB mstr_discrete
J 0
(-2650 3850);
PAINT MONO (-2650 3850);
DISPLAY INVISIBLE (-2650 3850);
FORCEADD RES..1
(-4425 4200);
FORCEPROP 1 LAST MATERIAL CHIP
J 0
(-4425 4025);
DISPLAY 0.617021 (-4425 4025);
PAINT SKYBLUE (-4425 4025);
FORCEPROP 1 LAST WATTAGE 1/16W
J 2
(-4450 4025);
DISPLAY 0.617021 (-4450 4025);
PAINT SKYBLUE (-4450 4025);
FORCEPROP 1 LAST PACK_TYPE 0402
J 0
(-4375 4075);
DISPLAY 0.617021 (-4375 4075);
PAINT SKYBLUE (-4375 4075);
FORCEPROP 1 LAST TOLERANCE 5%
J 0
(-4475 4075);
DISPLAY 0.617021 (-4475 4075);
PAINT SKYBLUE (-4475 4075);
FORCEPROP 1 LAST VALUE 0.0
J 2
(-4525 4075);
DISPLAY 0.617021 (-4525 4075);
PAINT SKYBLUE (-4525 4075);
FORCEPROP 1 LASTPIN (-4525 4200) $PN 1
J 0
(-4513 4212);
DISPLAY 0.617021 (-4513 4212);
PAINT WHITE (-4513 4212);
FORCEPROP 1 LASTPIN (-4325 4200) $PN 2
J 0
(-4363 4212);
DISPLAY 0.617021 (-4363 4212);
PAINT WHITE (-4363 4212);
FORCEPROP 1 LAST LOCATION R7B19
J 0
(-4475 4250);
DISPLAY 0.617021 (-4475 4250);
PAINT AQUA (-4475 4250);
FORCEPROP 1 LAST PART_NUMBER G21497-005
J 0
(-4575 4125);
DISPLAY 0.617021 (-4575 4125);
PAINT BLUE (-4575 4125);
FORCEPROP 2 LAST CDS_LIB mstr_discrete
J 0
(-4425 4200);
PAINT MONO (-4425 4200);
DISPLAY INVISIBLE (-4425 4200);
FORCEPROP 2 LAST BOM_COST PVPP_KLM_VR
J 0
(-4425 4200);
PAINT WHITE (-4425 4200);
DISPLAY INVISIBLE (-4425 4200);
FORCEPROP 2 LAST ROOM PVPP_KLM_VR
J 0
(-4425 4200);
PAINT GREEN (-4425 4200);
DISPLAY INVISIBLE (-4425 4200);
FORCEPROP 1 LAST PATH I240
J 0
(-4475 4350);
DISPLAY 0.978723 (-4475 4350);
PAINT WHITE (-4475 4350);
DISPLAY INVISIBLE (-4475 4350);
FORCEPROP 0 LAST SPOF TRUE
J 0
(-4475 4350);
DISPLAY 1.021277 (-4475 4350);
PAINT ORANGE (-4475 4350);
DISPLAY INVISIBLE (-4475 4350);
FORCEPROP 2 LAST CDS_SEC 1
J 0
(-4475 4400);
DISPLAY 1.042553 (-4475 4400);
PAINT ORANGE (-4475 4400);
DISPLAY INVISIBLE (-4475 4400);
FORCEPROP 2 LAST $SEC 1
J 0
(-4475 4400);
DISPLAY 0.680851 (-4475 4400);
PAINT MONO (-4475 4400);
DISPLAY INVISIBLE (-4475 4400);
FORCEPROP 2 LAST REUSE_ID 13
J 0
(-4475 4400);
DISPLAY 1.042553 (-4475 4400);
PAINT ORANGE (-4475 4400);
DISPLAY INVISIBLE (-4475 4400);
FORCEADD CAP..2
R 2
(-3725 4200);
FORCEPROP 1 LAST MATERIAL X7R
J 2
(-3725 4050);
DISPLAY 0.617021 (-3725 4050);
PAINT SKYBLUE (-3725 4050);
FORCEPROP 1 LAST PACK_TYPE 0603LF
J 1
(-3725 4000);
DISPLAY 0.617021 (-3725 4000);
PAINT SKYBLUE (-3725 4000);
FORCEPROP 1 LAST TOLERANCE 10%
J 0
(-3725 4050);
DISPLAY 0.617021 (-3725 4050);
PAINT SKYBLUE (-3725 4050);
FORCEPROP 1 LASTPIN (-3625 4200) $PN 1
J 2
(-3615 4215);
DISPLAY 0.617021 (-3615 4215);
PAINT WHITE (-3615 4215);
FORCEPROP 1 LASTPIN (-3825 4200) $PN 2
J 2
(-3810 4215);
DISPLAY 0.617021 (-3810 4215);
PAINT WHITE (-3810 4215);
FORCEPROP 1 LAST LOCATION C7B30
J 1
(-3725 4300);
DISPLAY 0.617021 (-3725 4300);
PAINT AQUA (-3725 4300);
FORCEPROP 1 LAST VOLTAGE 25V
J 2
(-3725 4100);
DISPLAY 0.617021 (-3725 4100);
PAINT SKYBLUE (-3725 4100);
FORCEPROP 1 LAST VALUE 0.1UF
J 0
(-3725 4100);
DISPLAY 0.617021 (-3725 4100);
PAINT SKYBLUE (-3725 4100);
FORCEPROP 1 LAST PART_NUMBER 602433-020
J 1
(-3725 4250);
DISPLAY 0.617021 (-3725 4250);
PAINT BLUE (-3725 4250);
FORCEPROP 2 LAST CDS_LIB mstr_discrete
J 0
(-3725 4200);
PAINT MONO (-3725 4200);
DISPLAY INVISIBLE (-3725 4200);
FORCEPROP 2 LAST ROOM PVPP_KLM_VR
J 2
(-3725 4325);
DISPLAY 0.765957 (-3725 4325);
PAINT GREEN (-3725 4325);
DISPLAY INVISIBLE (-3725 4325);
FORCEPROP 2 LAST REUSE_ID 27
J 0
(-3725 4450);
DISPLAY 1.042553 (-3725 4450);
PAINT ORANGE (-3725 4450);
DISPLAY INVISIBLE (-3725 4450);
FORCEPROP 0 LAST SPOF TRUE
J 0
(-3725 4400);
DISPLAY 1.021277 (-3725 4400);
PAINT ORANGE (-3725 4400);
DISPLAY INVISIBLE (-3725 4400);
FORCEPROP 2 LAST CDS_SEC 1
J 0
(-3770 4410);
DISPLAY 1.042553 (-3770 4410);
PAINT ORANGE (-3770 4410);
DISPLAY INVISIBLE (-3770 4410);
FORCEPROP 2 LAST $SEC 1
J 0
(-3725 4450);
DISPLAY 0.680851 (-3725 4450);
PAINT MONO (-3725 4450);
DISPLAY INVISIBLE (-3725 4450);
FORCEPROP 2 LAST BOM_COST PVPP_KLM_VR
J 0
(-3770 4360);
DISPLAY 1.042553 (-3770 4360);
PAINT WHITE (-3770 4360);
DISPLAY INVISIBLE (-3770 4360);
FORCEPROP 1 LAST PATH I241
J 2
(-3725 4400);
DISPLAY 0.978723 (-3725 4400);
PAINT WHITE (-3725 4400);
DISPLAY INVISIBLE (-3725 4400);
FORCEADD AGND_SCSI..1
(-6125 2025);
FORCEPROP 3 LASTPIN (-6125 2075) SIG_NAME AGND_PVPP_DEF\g
J 0
(-6115 2085);
DISPLAY 0.659574 (-6115 2085);
PAINT MONO (-6115 2085);
DISPLAY INVISIBLE (-6115 2085);
FORCEPROP 1 LAST HDL_POWER AGND_PVPP_DEF
J 1
(-6050 1950);
DISPLAY 0.617021 (-6050 1950);
PAINT GREEN (-6050 1950);
FORCEPROP 2 LAST ROOM PVPP_KLM_VR
J 0
(-6275 1975);
DISPLAY 1.042553 (-6275 1975);
PAINT GREEN (-6275 1975);
DISPLAY INVISIBLE (-6275 1975);
FORCEPROP 1 LAST BODY_TYPE PLUMBING
J 0
(-6170 1982);
DISPLAY 0.340426 (-6170 1982);
PAINT GREEN (-6170 1982);
DISPLAY INVISIBLE (-6170 1982);
FORCEPROP 2 LAST BOM_COST PVPP_KLM_VR
J 0
(-6275 1975);
DISPLAY 1.042553 (-6275 1975);
PAINT WHITE (-6275 1975);
DISPLAY INVISIBLE (-6275 1975);
FORCEPROP 1 LAST VOLTAGE 0.0V
J 0
(-6170 1982);
DISPLAY 0.340426 (-6170 1982);
PAINT SKYBLUE (-6170 1982);
DISPLAY INVISIBLE (-6170 1982);
FORCEPROP 1 LAST PATH I247
J 0
(-6050 2025);
DISPLAY 0.872340 (-6050 2025);
PAINT AQUA (-6050 2025);
DISPLAY INVISIBLE (-6050 2025);
FORCEPROP 2 LAST CDS_LIB mstr_symbols
J 0
(-6125 2025);
PAINT MONO (-6125 2025);
DISPLAY INVISIBLE (-6125 2025);
FORCEADD AGND_SCSI..1
(-5425 1950);
FORCEPROP 3 LASTPIN (-5425 2000) SIG_NAME AGND_PVPP_DEF\g
J 0
(-5415 2010);
DISPLAY 0.659574 (-5415 2010);
PAINT MONO (-5415 2010);
DISPLAY INVISIBLE (-5415 2010);
FORCEPROP 1 LAST HDL_POWER AGND_PVPP_DEF
J 1
(-5350 1875);
DISPLAY 0.617021 (-5350 1875);
PAINT GREEN (-5350 1875);
FORCEPROP 2 LAST ROOM PVPP_KLM_VR
J 0
(-5575 1900);
DISPLAY 1.042553 (-5575 1900);
PAINT GREEN (-5575 1900);
DISPLAY INVISIBLE (-5575 1900);
FORCEPROP 1 LAST BODY_TYPE PLUMBING
J 0
(-5470 1907);
DISPLAY 0.340426 (-5470 1907);
PAINT GREEN (-5470 1907);
DISPLAY INVISIBLE (-5470 1907);
FORCEPROP 2 LAST CDS_LIB mstr_symbols
J 0
(-5425 1950);
PAINT MONO (-5425 1950);
DISPLAY INVISIBLE (-5425 1950);
FORCEPROP 1 LAST VOLTAGE 0.0V
J 0
(-5470 1907);
DISPLAY 0.340426 (-5470 1907);
PAINT SKYBLUE (-5470 1907);
DISPLAY INVISIBLE (-5470 1907);
FORCEPROP 2 LAST BOM_COST PVPP_KLM_VR
J 0
(-5575 1900);
DISPLAY 1.042553 (-5575 1900);
PAINT WHITE (-5575 1900);
DISPLAY INVISIBLE (-5575 1900);
FORCEPROP 1 LAST PATH I248
J 0
(-5350 1950);
DISPLAY 0.872340 (-5350 1950);
PAINT AQUA (-5350 1950);
DISPLAY INVISIBLE (-5350 1950);
FORCEADD AGND_SCSI..1
(-4725 1850);
FORCEPROP 3 LASTPIN (-4725 1900) SIG_NAME AGND_PVPP_DEF\g
J 0
(-4715 1910);
DISPLAY 0.659574 (-4715 1910);
PAINT MONO (-4715 1910);
DISPLAY INVISIBLE (-4715 1910);
FORCEPROP 1 LAST HDL_POWER AGND_PVPP_DEF
J 1
(-4650 1775);
DISPLAY 0.617021 (-4650 1775);
PAINT GREEN (-4650 1775);
FORCEPROP 2 LAST BOM_COST PVPP_KLM_VR
J 0
(-4875 1800);
DISPLAY 1.042553 (-4875 1800);
PAINT WHITE (-4875 1800);
DISPLAY INVISIBLE (-4875 1800);
FORCEPROP 2 LAST ROOM PVPP_KLM_VR
J 0
(-4875 1800);
DISPLAY 1.042553 (-4875 1800);
PAINT GREEN (-4875 1800);
DISPLAY INVISIBLE (-4875 1800);
FORCEPROP 1 LAST BODY_TYPE PLUMBING
J 0
(-4770 1807);
DISPLAY 0.340426 (-4770 1807);
PAINT GREEN (-4770 1807);
DISPLAY INVISIBLE (-4770 1807);
FORCEPROP 1 LAST VOLTAGE 0.0V
J 0
(-4770 1807);
DISPLAY 0.340426 (-4770 1807);
PAINT SKYBLUE (-4770 1807);
DISPLAY INVISIBLE (-4770 1807);
FORCEPROP 1 LAST PATH I249
J 0
(-4650 1850);
DISPLAY 0.872340 (-4650 1850);
PAINT AQUA (-4650 1850);
DISPLAY INVISIBLE (-4650 1850);
FORCEPROP 2 LAST CDS_LIB mstr_symbols
J 0
(-4725 1850);
PAINT MONO (-4725 1850);
DISPLAY INVISIBLE (-4725 1850);
FORCEADD AGND_SCSI..1
(-5100 1350);
FORCEPROP 3 LASTPIN (-5100 1400) SIG_NAME AGND_PVPP_DEF\g
J 0
(-5090 1410);
DISPLAY 0.659574 (-5090 1410);
PAINT MONO (-5090 1410);
DISPLAY INVISIBLE (-5090 1410);
FORCEPROP 1 LAST HDL_POWER AGND_PVPP_DEF
J 1
(-5025 1275);
DISPLAY 0.617021 (-5025 1275);
PAINT GREEN (-5025 1275);
FORCEPROP 1 LAST BODY_TYPE PLUMBING
J 0
(-5145 1307);
DISPLAY 0.340426 (-5145 1307);
PAINT GREEN (-5145 1307);
DISPLAY INVISIBLE (-5145 1307);
FORCEPROP 1 LAST PATH I250
J 0
(-5025 1350);
DISPLAY 0.872340 (-5025 1350);
PAINT AQUA (-5025 1350);
DISPLAY INVISIBLE (-5025 1350);
FORCEPROP 2 LAST CDS_LIB mstr_symbols
J 0
(-5100 1350);
PAINT MONO (-5100 1350);
DISPLAY INVISIBLE (-5100 1350);
FORCEPROP 1 LAST VOLTAGE 0
J 0
(-5025 1375);
DISPLAY 1.021277 (-5025 1375);
PAINT SKYBLUE (-5025 1375);
DISPLAY INVISIBLE (-5025 1375);
FORCEADD AGND_SCSI..1
(-6825 2125);
FORCEPROP 3 LASTPIN (-6825 2175) SIG_NAME AGND_PVPP_DEF\g
J 0
(-6815 2185);
DISPLAY 0.659574 (-6815 2185);
PAINT MONO (-6815 2185);
DISPLAY INVISIBLE (-6815 2185);
FORCEPROP 1 LAST HDL_POWER AGND_PVPP_DEF
J 1
(-6750 2050);
DISPLAY 0.617021 (-6750 2050);
PAINT GREEN (-6750 2050);
FORCEPROP 2 LAST ROOM PVPP_KLM_VR
J 0
(-6975 2075);
DISPLAY 1.042553 (-6975 2075);
PAINT GREEN (-6975 2075);
DISPLAY INVISIBLE (-6975 2075);
FORCEPROP 2 LAST BOM_COST PVPP_KLM_VR
J 0
(-6975 2075);
DISPLAY 1.042553 (-6975 2075);
PAINT WHITE (-6975 2075);
DISPLAY INVISIBLE (-6975 2075);
FORCEPROP 1 LAST PATH I251
J 0
(-6750 2125);
DISPLAY 0.872340 (-6750 2125);
PAINT AQUA (-6750 2125);
DISPLAY INVISIBLE (-6750 2125);
FORCEPROP 1 LAST BODY_TYPE PLUMBING
J 0
(-6870 2082);
DISPLAY 0.340426 (-6870 2082);
PAINT GREEN (-6870 2082);
DISPLAY INVISIBLE (-6870 2082);
FORCEPROP 2 LAST CDS_LIB mstr_symbols
J 0
(-6825 2125);
PAINT MONO (-6825 2125);
DISPLAY INVISIBLE (-6825 2125);
FORCEPROP 1 LAST VOLTAGE 0.0V
J 0
(-6870 2082);
DISPLAY 0.340426 (-6870 2082);
PAINT SKYBLUE (-6870 2082);
DISPLAY INVISIBLE (-6870 2082);
FORCEADD CAP_A..1
(-5475 3525);
FORCEPROP 1 LASTPIN (-5475 3425) $PN 2
J 0
(-5465 3405);
DISPLAY 0.617021 (-5465 3405);
PAINT ORANGE (-5465 3405);
FORCEPROP 1 LAST MATERIAL X7R
J 0
(-5425 3425);
DISPLAY 0.617021 (-5425 3425);
PAINT SKYBLUE (-5425 3425);
FORCEPROP 1 LAST VOLTAGE 16V
J 0
(-5425 3525);
DISPLAY 0.617021 (-5425 3525);
PAINT SKYBLUE (-5425 3525);
FORCEPROP 1 LAST PACK_TYPE 0402V
J 0
(-5425 3325);
DISPLAY 0.617021 (-5425 3325);
PAINT SKYBLUE (-5425 3325);
FORCEPROP 1 LAST TOLERANCE 10%
J 0
(-5425 3475);
DISPLAY 0.617021 (-5425 3475);
PAINT SKYBLUE (-5425 3475);
FORCEPROP 1 LAST PART_NUMBER A36096-030
J 0
(-5425 3375);
DISPLAY 0.617021 (-5425 3375);
PAINT BLUE (-5425 3375);
FORCEPROP 1 LAST VALUE 0.1UF
J 0
(-5425 3575);
DISPLAY 0.617021 (-5425 3575);
PAINT SKYBLUE (-5425 3575);
FORCEPROP 1 LASTPIN (-5475 3625) $PN 1
J 0
(-5465 3605);
DISPLAY 0.617021 (-5465 3605);
PAINT ORANGE (-5465 3605);
FORCEPROP 1 LAST LOCATION C7B6
J 0
(-5425 3625);
DISPLAY 0.617021 (-5425 3625);
PAINT AQUA (-5425 3625);
FORCEPROP 2 LAST CDS_LIB dev_discrete
J 0
(-5475 3525);
PAINT ORANGE (-5475 3525);
DISPLAY INVISIBLE (-5475 3525);
FORCEPROP 1 LAST PATH I252
J 0
(-5425 3675);
DISPLAY 0.978723 (-5425 3675);
PAINT WHITE (-5425 3675);
DISPLAY INVISIBLE (-5425 3675);
FORCEPROP 2 LAST CDS_LOCATION C7B6
J 0
(-5425 3625);
DISPLAY 0.617021 (-5425 3625);
PAINT AQUA (-5425 3625);
DISPLAY INVISIBLE (-5425 3625);
FORCEPROP 2 LAST CDS_SEC 1
J 0
(-5425 3675);
PAINT ORANGE (-5425 3675);
DISPLAY INVISIBLE (-5425 3675);
FORCEPROP 2 LAST SEC_TYPE 0402V
J 0
(-5425 3725);
DISPLAY 1.021277 (-5425 3725);
PAINT ORANGE (-5425 3725);
DISPLAY INVISIBLE (-5425 3725);
FORCEPROP 2 LAST SEC 1
J 0
(-5425 3725);
DISPLAY 0.680851 (-5425 3725);
PAINT MONO (-5425 3725);
DISPLAY INVISIBLE (-5425 3725);
FORCEADD CAP..1
(-6125 2425);
FORCEPROP 1 LAST MATERIAL X6S
J 0
(-6075 2225);
DISPLAY 0.617021 (-6075 2225);
PAINT SKYBLUE (-6075 2225);
FORCEPROP 1 LAST LOCATION C3M10
J 0
(-6075 2525);
DISPLAY 0.617021 (-6075 2525);
PAINT AQUA (-6075 2525);
FORCEPROP 1 LASTPIN (-6125 2525) $PN 1
J 0
(-6115 2505);
DISPLAY 0.617021 (-6115 2505);
PAINT ORANGE (-6115 2505);
FORCEPROP 1 LASTPIN (-6125 2325) $PN 2
J 0
(-6115 2305);
DISPLAY 0.617021 (-6115 2305);
PAINT ORANGE (-6115 2305);
FORCEPROP 1 LAST VOLTAGE 6.3V
J 0
(-6050 2425);
DISPLAY 0.617021 (-6050 2425);
PAINT SKYBLUE (-6050 2425);
FORCEPROP 1 LAST PACK_TYPE 0603
J 0
(-6075 2325);
DISPLAY 0.617021 (-6075 2325);
PAINT SKYBLUE (-6075 2325);
FORCEPROP 1 LAST TOLERANCE 10%
J 0
(-6050 2375);
DISPLAY 0.617021 (-6050 2375);
PAINT SKYBLUE (-6050 2375);
FORCEPROP 1 LAST VALUE 4.7UF
J 0
(-6075 2475);
DISPLAY 0.617021 (-6075 2475);
PAINT SKYBLUE (-6075 2475);
FORCEPROP 1 LAST PART_NUMBER E15431-003
J 0
(-6100 2275);
DISPLAY 0.617021 (-6100 2275);
PAINT BLUE (-6100 2275);
FORCEPROP 2 LAST CDS_LOCATION C3M10
J 0
(-6075 2525);
DISPLAY 0.617021 (-6075 2525);
PAINT AQUA (-6075 2525);
DISPLAY INVISIBLE (-6075 2525);
FORCEPROP 2 LAST CDS_LIB mstr_discrete
J 0
(-6125 2425);
PAINT MONO (-6125 2425);
DISPLAY INVISIBLE (-6125 2425);
FORCEPROP 2 LAST ROOM PVPP_KLM_VR
J 0
(-6075 2550);
PAINT GREEN (-6075 2550);
DISPLAY INVISIBLE (-6075 2550);
FORCEPROP 1 LAST PATH I253
J 0
(-6075 2575);
DISPLAY 0.978723 (-6075 2575);
PAINT WHITE (-6075 2575);
DISPLAY INVISIBLE (-6075 2575);
FORCEPROP 2 LAST SEC 1
J 0
(-6075 2625);
DISPLAY 0.680851 (-6075 2625);
PAINT MONO (-6075 2625);
DISPLAY INVISIBLE (-6075 2625);
FORCEPROP 2 LAST BOM_COST PVPP_KLM_VR
J 0
(-6075 2575);
DISPLAY 1.042553 (-6075 2575);
PAINT WHITE (-6075 2575);
DISPLAY INVISIBLE (-6075 2575);
FORCEPROP 2 LAST SEC_TYPE 0603
J 0
(-6075 2625);
DISPLAY 1.021277 (-6075 2625);
PAINT ORANGE (-6075 2625);
DISPLAY INVISIBLE (-6075 2625);
FORCEPROP 2 LAST REUSE_ID 26
J 0
(-6075 2625);
DISPLAY 1.042553 (-6075 2625);
PAINT ORANGE (-6075 2625);
DISPLAY INVISIBLE (-6075 2625);
FORCEADD AGND_SCSI..1
(-5775 2725);
FORCEPROP 3 LASTPIN (-5775 2775) SIG_NAME AGND_PVPP_DEF\g
J 0
(-5765 2785);
DISPLAY 0.659574 (-5765 2785);
PAINT MONO (-5765 2785);
DISPLAY INVISIBLE (-5765 2785);
FORCEPROP 1 LAST HDL_POWER AGND_PVPP_DEF
J 1
(-5700 2650);
DISPLAY 0.617021 (-5700 2650);
PAINT GREEN (-5700 2650);
FORCEPROP 2 LAST BOM_COST PVPP_KLM_VR
J 0
(-5925 2675);
DISPLAY 1.042553 (-5925 2675);
PAINT WHITE (-5925 2675);
DISPLAY INVISIBLE (-5925 2675);
FORCEPROP 2 LAST ROOM PVPP_KLM_VR
J 0
(-5925 2675);
DISPLAY 1.042553 (-5925 2675);
PAINT GREEN (-5925 2675);
DISPLAY INVISIBLE (-5925 2675);
FORCEPROP 1 LAST VOLTAGE 0.0V
J 0
(-5820 2682);
DISPLAY 0.340426 (-5820 2682);
PAINT SKYBLUE (-5820 2682);
DISPLAY INVISIBLE (-5820 2682);
FORCEPROP 2 LAST CDS_LIB mstr_symbols
J 0
(-5775 2725);
PAINT MONO (-5775 2725);
DISPLAY INVISIBLE (-5775 2725);
FORCEPROP 1 LAST BODY_TYPE PLUMBING
J 0
(-5820 2682);
DISPLAY 0.340426 (-5820 2682);
PAINT GREEN (-5820 2682);
DISPLAY INVISIBLE (-5820 2682);
FORCEPROP 1 LAST PATH I254
J 0
(-5700 2725);
DISPLAY 0.872340 (-5700 2725);
PAINT AQUA (-5700 2725);
DISPLAY INVISIBLE (-5700 2725);
FORCEADD GND..1
(-5475 3275);
FORCEPROP 3 LASTPIN (-5475 3325) SIG_NAME GND\g
J 0
(-5465 3335);
DISPLAY 0.659574 (-5465 3335);
PAINT MONO (-5465 3335);
DISPLAY INVISIBLE (-5465 3335);
FORCEPROP 2 LAST BOM_COST PVPP_KLM_VR
J 0
(-6325 3350);
DISPLAY 1.042553 (-6325 3350);
PAINT WHITE (-6325 3350);
DISPLAY INVISIBLE (-6325 3350);
FORCEPROP 2 LAST ROOM PVPP_KLM_VR
J 0
(-6050 3350);
DISPLAY 1.042553 (-6050 3350);
PAINT GREEN (-6050 3350);
DISPLAY INVISIBLE (-6050 3350);
FORCEPROP 1 LAST PATH I255
J 0
(-5400 3275);
DISPLAY 0.872340 (-5400 3275);
PAINT AQUA (-5400 3275);
DISPLAY INVISIBLE (-5400 3275);
FORCEPROP 1 LAST BODY_TYPE PLUMBING
J 0
(-5520 3232);
DISPLAY 0.340426 (-5520 3232);
PAINT GREEN (-5520 3232);
DISPLAY INVISIBLE (-5520 3232);
FORCEPROP 1 LAST SIZE 1B
J 0
(-5400 3225);
DISPLAY 0.872340 (-5400 3225);
PAINT GREEN (-5400 3225);
DISPLAY INVISIBLE (-5400 3225);
FORCEPROP 2 LAST CDS_LIB mstr_symbols
J 0
(-5475 3275);
PAINT MONO (-5475 3275);
DISPLAY INVISIBLE (-5475 3275);
FORCEPROP 1 LAST VOLTAGE 0
J 0
(-5475 3275);
PAINT SKYBLUE (-5475 3275);
DISPLAY INVISIBLE (-5475 3275);
FORCEPROP 1 LAST HDL_POWER GND
J 0
(-5475 3425);
DISPLAY 0.872340 (-5475 3425);
PAINT GREEN (-5475 3425);
DISPLAY INVISIBLE (-5475 3425);
FORCEADD RES..1
(-3875 975);
FORCEPROP 1 LAST VALUE 22.1
J 2
(-3900 875);
DISPLAY 0.617021 (-3900 875);
PAINT SKYBLUE (-3900 875);
FORCEPROP 1 LAST WATTAGE 1/16W
J 2
(-3900 825);
DISPLAY 0.617021 (-3900 825);
PAINT SKYBLUE (-3900 825);
FORCEPROP 1 LASTPIN (-3975 975) $PN 1
J 0
(-3963 987);
DISPLAY 0.617021 (-3963 987);
PAINT ORANGE (-3963 987);
FORCEPROP 1 LAST TOLERANCE 1.0%
J 0
(-3875 875);
DISPLAY 0.617021 (-3875 875);
PAINT SKYBLUE (-3875 875);
FORCEPROP 1 LAST MATERIAL CHIP
J 0
(-3875 825);
DISPLAY 0.617021 (-3875 825);
PAINT SKYBLUE (-3875 825);
FORCEPROP 1 LASTPIN (-3775 975) $PN 2
J 0
(-3813 987);
DISPLAY 0.617021 (-3813 987);
PAINT ORANGE (-3813 987);
FORCEPROP 1 LAST PACK_TYPE 0402
J 0
(-3625 825);
DISPLAY 0.617021 (-3625 825);
PAINT SKYBLUE (-3625 825);
FORCEPROP 1 LAST LOCATION R7B12
J 0
(-3925 1025);
DISPLAY 0.617021 (-3925 1025);
PAINT AQUA (-3925 1025);
FORCEPROP 1 LAST PART_NUMBER G21796-250
J 0
(-3925 1075);
DISPLAY 0.617021 (-3925 1075);
PAINT BLUE (-3925 1075);
FORCEPROP 2 LAST CDS_LIB mstr_discrete
J 0
(-3875 975);
PAINT MONO (-3875 975);
DISPLAY INVISIBLE (-3875 975);
FORCEPROP 2 LAST SEC_TYPE 0402
J 0
(-3925 1175);
DISPLAY 1.021277 (-3925 1175);
PAINT ORANGE (-3925 1175);
DISPLAY INVISIBLE (-3925 1175);
FORCEPROP 2 LAST SEC 1
J 0
(-3925 1175);
DISPLAY 0.680851 (-3925 1175);
PAINT MONO (-3925 1175);
DISPLAY INVISIBLE (-3925 1175);
FORCEPROP 2 LAST CDS_LOCATION R7B12
J 0
(-3925 1025);
DISPLAY 0.617021 (-3925 1025);
PAINT AQUA (-3925 1025);
DISPLAY INVISIBLE (-3925 1025);
FORCEPROP 1 LAST PATH I257
J 0
(-3925 1125);
DISPLAY 0.978723 (-3925 1125);
PAINT WHITE (-3925 1125);
DISPLAY INVISIBLE (-3925 1125);
FORCEPROP 2 LAST ROOM PVPP_DEF_VR
J 0
(-3925 1075);
DISPLAY 1.361702 (-3925 1075);
PAINT ORANGE (-3925 1075);
DISPLAY INVISIBLE (-3925 1075);
FORCEADD CAP..1
(-6975 4100);
FORCEPROP 1 LASTPIN (-6975 4000) $PN 2
J 0
(-6965 3980);
DISPLAY 0.617021 (-6965 3980);
PAINT ORANGE (-6965 3980);
FORCEPROP 1 LAST MATERIAL X6S
J 0
(-6925 4000);
DISPLAY 0.617021 (-6925 4000);
PAINT SKYBLUE (-6925 4000);
FORCEPROP 1 LAST PACK_TYPE 0805
J 0
(-6925 3900);
DISPLAY 0.617021 (-6925 3900);
PAINT SKYBLUE (-6925 3900);
FORCEPROP 1 LAST TOLERANCE 10%
J 0
(-6925 4050);
DISPLAY 0.617021 (-6925 4050);
PAINT SKYBLUE (-6925 4050);
FORCEPROP 1 LAST PART_NUMBER C95333-007
J 0
(-6925 3950);
DISPLAY 0.617021 (-6925 3950);
PAINT BLUE (-6925 3950);
FORCEPROP 1 LASTPIN (-6975 4200) $PN 1
J 0
(-6965 4180);
DISPLAY 0.617021 (-6965 4180);
PAINT ORANGE (-6965 4180);
FORCEPROP 1 LAST VOLTAGE 16V
J 0
(-6925 4100);
DISPLAY 0.617021 (-6925 4100);
PAINT SKYBLUE (-6925 4100);
FORCEPROP 1 LAST VALUE 10UF
J 0
(-6925 4150);
DISPLAY 0.617021 (-6925 4150);
PAINT SKYBLUE (-6925 4150);
FORCEPROP 1 LAST LOCATION C3M8
J 0
(-6925 4200);
DISPLAY 0.617021 (-6925 4200);
PAINT AQUA (-6925 4200);
FORCEPROP 2 LAST CDS_LIB mstr_discrete
J 0
(-6975 4100);
PAINT MONO (-6975 4100);
DISPLAY INVISIBLE (-6975 4100);
FORCEPROP 2 LAST CDS_LOCATION C3M8
J 0
(-6925 4200);
DISPLAY 0.617021 (-6925 4200);
PAINT AQUA (-6925 4200);
DISPLAY INVISIBLE (-6925 4200);
FORCEPROP 2 LAST SEC_TYPE 0805
J 0
(-6925 4300);
DISPLAY 1.021277 (-6925 4300);
PAINT ORANGE (-6925 4300);
DISPLAY INVISIBLE (-6925 4300);
FORCEPROP 2 LAST SEC 1
J 0
(-6925 4300);
DISPLAY 0.680851 (-6925 4300);
PAINT MONO (-6925 4300);
DISPLAY INVISIBLE (-6925 4300);
FORCEPROP 1 LAST PATH I259
J 0
(-6925 4250);
DISPLAY 0.978723 (-6925 4250);
PAINT WHITE (-6925 4250);
DISPLAY INVISIBLE (-6925 4250);
FORCEADD CAP..1
(-6600 4100);
FORCEPROP 1 LASTPIN (-6600 4000) $PN 2
J 0
(-6590 3980);
DISPLAY 0.617021 (-6590 3980);
PAINT ORANGE (-6590 3980);
FORCEPROP 1 LAST MATERIAL X6S
J 0
(-6550 4000);
DISPLAY 0.617021 (-6550 4000);
PAINT SKYBLUE (-6550 4000);
FORCEPROP 1 LAST PACK_TYPE 0805
J 0
(-6550 3900);
DISPLAY 0.617021 (-6550 3900);
PAINT SKYBLUE (-6550 3900);
FORCEPROP 1 LAST TOLERANCE 10%
J 0
(-6550 4050);
DISPLAY 0.617021 (-6550 4050);
PAINT SKYBLUE (-6550 4050);
FORCEPROP 1 LAST PART_NUMBER C95333-007
J 0
(-6550 3950);
DISPLAY 0.617021 (-6550 3950);
PAINT BLUE (-6550 3950);
FORCEPROP 1 LASTPIN (-6600 4200) $PN 1
J 0
(-6590 4180);
DISPLAY 0.617021 (-6590 4180);
PAINT ORANGE (-6590 4180);
FORCEPROP 1 LAST VOLTAGE 16V
J 0
(-6550 4100);
DISPLAY 0.617021 (-6550 4100);
PAINT SKYBLUE (-6550 4100);
FORCEPROP 1 LAST VALUE 10UF
J 0
(-6550 4150);
DISPLAY 0.617021 (-6550 4150);
PAINT SKYBLUE (-6550 4150);
FORCEPROP 1 LAST LOCATION C3M15
J 0
(-6550 4200);
DISPLAY 0.617021 (-6550 4200);
PAINT AQUA (-6550 4200);
FORCEPROP 2 LAST CDS_LIB mstr_discrete
J 0
(-6600 4100);
PAINT MONO (-6600 4100);
DISPLAY INVISIBLE (-6600 4100);
FORCEPROP 2 LAST CDS_LOCATION C3M15
J 0
(-6550 4200);
DISPLAY 0.617021 (-6550 4200);
PAINT AQUA (-6550 4200);
DISPLAY INVISIBLE (-6550 4200);
FORCEPROP 2 LAST SEC_TYPE 0805
J 0
(-6550 4300);
DISPLAY 1.021277 (-6550 4300);
PAINT ORANGE (-6550 4300);
DISPLAY INVISIBLE (-6550 4300);
FORCEPROP 2 LAST SEC 1
J 0
(-6550 4300);
DISPLAY 0.680851 (-6550 4300);
PAINT MONO (-6550 4300);
DISPLAY INVISIBLE (-6550 4300);
FORCEPROP 1 LAST PATH I260
J 0
(-6550 4250);
DISPLAY 0.978723 (-6550 4250);
PAINT WHITE (-6550 4250);
DISPLAY INVISIBLE (-6550 4250);
FORCEADD CAP..1
(-6225 4100);
FORCEPROP 1 LASTPIN (-6225 4000) $PN 2
J 0
(-6215 3980);
DISPLAY 0.617021 (-6215 3980);
PAINT ORANGE (-6215 3980);
FORCEPROP 1 LAST MATERIAL X6S
J 0
(-6175 4000);
DISPLAY 0.617021 (-6175 4000);
PAINT SKYBLUE (-6175 4000);
FORCEPROP 1 LAST PACK_TYPE 0805
J 0
(-6175 3900);
DISPLAY 0.617021 (-6175 3900);
PAINT SKYBLUE (-6175 3900);
FORCEPROP 1 LAST TOLERANCE 10%
J 0
(-6175 4050);
DISPLAY 0.617021 (-6175 4050);
PAINT SKYBLUE (-6175 4050);
FORCEPROP 1 LAST PART_NUMBER C95333-007
J 0
(-6175 3950);
DISPLAY 0.617021 (-6175 3950);
PAINT BLUE (-6175 3950);
FORCEPROP 1 LASTPIN (-6225 4200) $PN 1
J 0
(-6215 4180);
DISPLAY 0.617021 (-6215 4180);
PAINT ORANGE (-6215 4180);
FORCEPROP 1 LAST VOLTAGE 16V
J 0
(-6175 4100);
DISPLAY 0.617021 (-6175 4100);
PAINT SKYBLUE (-6175 4100);
FORCEPROP 1 LAST VALUE 10UF
J 0
(-6175 4150);
DISPLAY 0.617021 (-6175 4150);
PAINT SKYBLUE (-6175 4150);
FORCEPROP 1 LAST LOCATION C3M16
J 0
(-6175 4200);
DISPLAY 0.617021 (-6175 4200);
PAINT AQUA (-6175 4200);
FORCEPROP 2 LAST CDS_LIB mstr_discrete
J 0
(-6225 4100);
PAINT MONO (-6225 4100);
DISPLAY INVISIBLE (-6225 4100);
FORCEPROP 2 LAST CDS_LOCATION C3M16
J 0
(-6175 4200);
DISPLAY 0.617021 (-6175 4200);
PAINT AQUA (-6175 4200);
DISPLAY INVISIBLE (-6175 4200);
FORCEPROP 2 LAST SEC_TYPE 0805
J 0
(-6175 4300);
DISPLAY 1.021277 (-6175 4300);
PAINT ORANGE (-6175 4300);
DISPLAY INVISIBLE (-6175 4300);
FORCEPROP 2 LAST SEC 1
J 0
(-6175 4300);
DISPLAY 0.680851 (-6175 4300);
PAINT MONO (-6175 4300);
DISPLAY INVISIBLE (-6175 4300);
FORCEPROP 1 LAST PATH I261
J 0
(-6175 4250);
DISPLAY 0.978723 (-6175 4250);
PAINT WHITE (-6175 4250);
DISPLAY INVISIBLE (-6175 4250);
FORCEADD CAP..1
(-5850 4100);
FORCEPROP 1 LASTPIN (-5850 4000) $PN 2
J 0
(-5840 3980);
DISPLAY 0.617021 (-5840 3980);
PAINT ORANGE (-5840 3980);
FORCEPROP 1 LAST MATERIAL X6S
J 0
(-5800 4000);
DISPLAY 0.617021 (-5800 4000);
PAINT SKYBLUE (-5800 4000);
FORCEPROP 1 LAST PACK_TYPE 0805
J 0
(-5800 3900);
DISPLAY 0.617021 (-5800 3900);
PAINT SKYBLUE (-5800 3900);
FORCEPROP 1 LAST TOLERANCE 10%
J 0
(-5800 4050);
DISPLAY 0.617021 (-5800 4050);
PAINT SKYBLUE (-5800 4050);
FORCEPROP 1 LAST PART_NUMBER C95333-007
J 0
(-5800 3950);
DISPLAY 0.617021 (-5800 3950);
PAINT BLUE (-5800 3950);
FORCEPROP 1 LASTPIN (-5850 4200) $PN 1
J 0
(-5840 4180);
DISPLAY 0.617021 (-5840 4180);
PAINT ORANGE (-5840 4180);
FORCEPROP 1 LAST VOLTAGE 16V
J 0
(-5800 4100);
DISPLAY 0.617021 (-5800 4100);
PAINT SKYBLUE (-5800 4100);
FORCEPROP 1 LAST VALUE 10UF
J 0
(-5800 4150);
DISPLAY 0.617021 (-5800 4150);
PAINT SKYBLUE (-5800 4150);
FORCEPROP 1 LAST LOCATION C7B5
J 0
(-5800 4200);
DISPLAY 0.617021 (-5800 4200);
PAINT AQUA (-5800 4200);
FORCEPROP 2 LAST CDS_LIB mstr_discrete
J 0
(-5850 4100);
PAINT MONO (-5850 4100);
DISPLAY INVISIBLE (-5850 4100);
FORCEPROP 2 LAST CDS_LOCATION C7B5
J 0
(-5800 4200);
DISPLAY 0.617021 (-5800 4200);
PAINT AQUA (-5800 4200);
DISPLAY INVISIBLE (-5800 4200);
FORCEPROP 2 LAST SEC_TYPE 0805
J 0
(-5800 4300);
DISPLAY 1.021277 (-5800 4300);
PAINT ORANGE (-5800 4300);
DISPLAY INVISIBLE (-5800 4300);
FORCEPROP 2 LAST SEC 1
J 0
(-5800 4300);
DISPLAY 0.680851 (-5800 4300);
PAINT MONO (-5800 4300);
DISPLAY INVISIBLE (-5800 4300);
FORCEPROP 1 LAST PATH I262
J 0
(-5800 4250);
DISPLAY 0.978723 (-5800 4250);
PAINT WHITE (-5800 4250);
DISPLAY INVISIBLE (-5800 4250);
FORCEADD GND..1
(-6975 3900);
FORCEPROP 3 LASTPIN (-6975 3950) SIG_NAME GND\g
J 0
(-6965 3960);
DISPLAY 0.659574 (-6965 3960);
PAINT MONO (-6965 3960);
DISPLAY INVISIBLE (-6965 3960);
FORCEPROP 2 LAST BOM_COST PVPP_KLM_VR
J 0
(-7825 3975);
DISPLAY 1.042553 (-7825 3975);
PAINT WHITE (-7825 3975);
DISPLAY INVISIBLE (-7825 3975);
FORCEPROP 2 LAST ROOM PVPP_KLM_VR
J 0
(-7550 3975);
DISPLAY 1.042553 (-7550 3975);
PAINT GREEN (-7550 3975);
DISPLAY INVISIBLE (-7550 3975);
FORCEPROP 1 LAST VOLTAGE 0
J 0
(-6975 3900);
PAINT SKYBLUE (-6975 3900);
DISPLAY INVISIBLE (-6975 3900);
FORCEPROP 2 LAST CDS_LIB mstr_symbols
J 0
(-6975 3900);
PAINT MONO (-6975 3900);
DISPLAY INVISIBLE (-6975 3900);
FORCEPROP 1 LAST BODY_TYPE PLUMBING
J 0
(-7020 3857);
DISPLAY 0.340426 (-7020 3857);
PAINT GREEN (-7020 3857);
DISPLAY INVISIBLE (-7020 3857);
FORCEPROP 1 LAST HDL_POWER GND
J 0
(-6975 4050);
DISPLAY 0.872340 (-6975 4050);
PAINT GREEN (-6975 4050);
DISPLAY INVISIBLE (-6975 4050);
FORCEPROP 1 LAST PATH I263
J 0
(-6900 3900);
DISPLAY 0.872340 (-6900 3900);
PAINT AQUA (-6900 3900);
DISPLAY INVISIBLE (-6900 3900);
FORCEPROP 1 LAST SIZE 1B
J 0
(-6900 3850);
DISPLAY 0.872340 (-6900 3850);
PAINT GREEN (-6900 3850);
DISPLAY INVISIBLE (-6900 3850);
FORCEADD GND..1
(-6600 3900);
FORCEPROP 3 LASTPIN (-6600 3950) SIG_NAME GND\g
J 0
(-6590 3960);
DISPLAY 0.659574 (-6590 3960);
PAINT MONO (-6590 3960);
DISPLAY INVISIBLE (-6590 3960);
FORCEPROP 2 LAST BOM_COST PVPP_KLM_VR
J 0
(-7450 3975);
DISPLAY 1.042553 (-7450 3975);
PAINT WHITE (-7450 3975);
DISPLAY INVISIBLE (-7450 3975);
FORCEPROP 2 LAST ROOM PVPP_KLM_VR
J 0
(-7175 3975);
DISPLAY 1.042553 (-7175 3975);
PAINT GREEN (-7175 3975);
DISPLAY INVISIBLE (-7175 3975);
FORCEPROP 1 LAST VOLTAGE 0
J 0
(-6600 3900);
PAINT SKYBLUE (-6600 3900);
DISPLAY INVISIBLE (-6600 3900);
FORCEPROP 2 LAST CDS_LIB mstr_symbols
J 0
(-6600 3900);
PAINT MONO (-6600 3900);
DISPLAY INVISIBLE (-6600 3900);
FORCEPROP 1 LAST BODY_TYPE PLUMBING
J 0
(-6645 3857);
DISPLAY 0.340426 (-6645 3857);
PAINT GREEN (-6645 3857);
DISPLAY INVISIBLE (-6645 3857);
FORCEPROP 1 LAST HDL_POWER GND
J 0
(-6600 4050);
DISPLAY 0.872340 (-6600 4050);
PAINT GREEN (-6600 4050);
DISPLAY INVISIBLE (-6600 4050);
FORCEPROP 1 LAST PATH I264
J 0
(-6525 3900);
DISPLAY 0.872340 (-6525 3900);
PAINT AQUA (-6525 3900);
DISPLAY INVISIBLE (-6525 3900);
FORCEPROP 1 LAST SIZE 1B
J 0
(-6525 3850);
DISPLAY 0.872340 (-6525 3850);
PAINT GREEN (-6525 3850);
DISPLAY INVISIBLE (-6525 3850);
FORCEADD GND..1
(-6225 3900);
FORCEPROP 3 LASTPIN (-6225 3950) SIG_NAME GND\g
J 0
(-6215 3960);
DISPLAY 0.659574 (-6215 3960);
PAINT MONO (-6215 3960);
DISPLAY INVISIBLE (-6215 3960);
FORCEPROP 2 LAST BOM_COST PVPP_KLM_VR
J 0
(-7075 3975);
DISPLAY 1.042553 (-7075 3975);
PAINT WHITE (-7075 3975);
DISPLAY INVISIBLE (-7075 3975);
FORCEPROP 2 LAST ROOM PVPP_KLM_VR
J 0
(-6800 3975);
DISPLAY 1.042553 (-6800 3975);
PAINT GREEN (-6800 3975);
DISPLAY INVISIBLE (-6800 3975);
FORCEPROP 1 LAST VOLTAGE 0
J 0
(-6225 3900);
PAINT SKYBLUE (-6225 3900);
DISPLAY INVISIBLE (-6225 3900);
FORCEPROP 2 LAST CDS_LIB mstr_symbols
J 0
(-6225 3900);
PAINT MONO (-6225 3900);
DISPLAY INVISIBLE (-6225 3900);
FORCEPROP 1 LAST SIZE 1B
J 0
(-6150 3850);
DISPLAY 0.872340 (-6150 3850);
PAINT GREEN (-6150 3850);
DISPLAY INVISIBLE (-6150 3850);
FORCEPROP 1 LAST BODY_TYPE PLUMBING
J 0
(-6270 3857);
DISPLAY 0.340426 (-6270 3857);
PAINT GREEN (-6270 3857);
DISPLAY INVISIBLE (-6270 3857);
FORCEPROP 1 LAST PATH I265
J 0
(-6150 3900);
DISPLAY 0.872340 (-6150 3900);
PAINT AQUA (-6150 3900);
DISPLAY INVISIBLE (-6150 3900);
FORCEPROP 1 LAST HDL_POWER GND
J 0
(-6225 4050);
DISPLAY 0.872340 (-6225 4050);
PAINT GREEN (-6225 4050);
DISPLAY INVISIBLE (-6225 4050);
FORCEADD GND..1
(-5850 3900);
FORCEPROP 3 LASTPIN (-5850 3950) SIG_NAME GND\g
J 0
(-5840 3960);
DISPLAY 0.659574 (-5840 3960);
PAINT MONO (-5840 3960);
DISPLAY INVISIBLE (-5840 3960);
FORCEPROP 2 LAST BOM_COST PVPP_KLM_VR
J 0
(-6700 3975);
DISPLAY 1.042553 (-6700 3975);
PAINT WHITE (-6700 3975);
DISPLAY INVISIBLE (-6700 3975);
FORCEPROP 2 LAST ROOM PVPP_KLM_VR
J 0
(-6425 3975);
DISPLAY 1.042553 (-6425 3975);
PAINT GREEN (-6425 3975);
DISPLAY INVISIBLE (-6425 3975);
FORCEPROP 1 LAST BODY_TYPE PLUMBING
J 0
(-5895 3857);
DISPLAY 0.340426 (-5895 3857);
PAINT GREEN (-5895 3857);
DISPLAY INVISIBLE (-5895 3857);
FORCEPROP 1 LAST VOLTAGE 0
J 0
(-5850 3900);
PAINT SKYBLUE (-5850 3900);
DISPLAY INVISIBLE (-5850 3900);
FORCEPROP 2 LAST CDS_LIB mstr_symbols
J 0
(-5850 3900);
PAINT MONO (-5850 3900);
DISPLAY INVISIBLE (-5850 3900);
FORCEPROP 1 LAST SIZE 1B
J 0
(-5775 3850);
DISPLAY 0.872340 (-5775 3850);
PAINT GREEN (-5775 3850);
DISPLAY INVISIBLE (-5775 3850);
FORCEPROP 1 LAST PATH I266
J 0
(-5775 3900);
DISPLAY 0.872340 (-5775 3900);
PAINT AQUA (-5775 3900);
DISPLAY INVISIBLE (-5775 3900);
FORCEPROP 1 LAST HDL_POWER GND
J 0
(-5850 4050);
DISPLAY 0.872340 (-5850 4050);
PAINT GREEN (-5850 4050);
DISPLAY INVISIBLE (-5850 4050);
FORCEADD CAPP..1
(-1800 3650);
FORCEPROP 1 LAST PACK_TYPE 7343
J 0
(-1750 3500);
DISPLAY 0.617021 (-1750 3500);
PAINT SKYBLUE (-1750 3500);
FORCEPROP 1 LAST MATERIAL POSCAP
J 0
(-1750 3550);
DISPLAY 0.617021 (-1750 3550);
PAINT SKYBLUE (-1750 3550);
FORCEPROP 1 LASTPIN (-1800 3550) $PN 2
J 0
(-1790 3535);
DISPLAY 0.617021 (-1790 3535);
PAINT ORANGE (-1790 3535);
FORCEPROP 1 LASTPIN (-1800 3750) $PN 1
J 0
(-1790 3735);
DISPLAY 0.617021 (-1790 3735);
PAINT ORANGE (-1790 3735);
FORCEPROP 1 LAST VOLTAGE 4V
J 0
(-1750 3600);
DISPLAY 0.617021 (-1750 3600);
PAINT SKYBLUE (-1750 3600);
FORCEPROP 1 LAST TOLERANCE 20%
J 0
(-1750 3650);
DISPLAY 0.617021 (-1750 3650);
PAINT SKYBLUE (-1750 3650);
FORCEPROP 1 LAST VALUE 220UF
J 0
(-1750 3700);
DISPLAY 0.617021 (-1750 3700);
PAINT SKYBLUE (-1750 3700);
FORCEPROP 1 LAST LOCATION C4M1
J 0
(-1750 3750);
DISPLAY 0.617021 (-1750 3750);
PAINT AQUA (-1750 3750);
FORCEPROP 1 LAST PART_NUMBER 724613-067
J 0
(-1750 3450);
DISPLAY 0.617021 (-1750 3450);
PAINT BLUE (-1750 3450);
FORCEPROP 2 LAST CDS_LIB mstr_discrete
J 0
(-1800 3650);
PAINT ORANGE (-1800 3650);
DISPLAY INVISIBLE (-1800 3650);
FORCEPROP 1 LAST PATH I267
J 0
(-1750 3800);
DISPLAY 0.978723 (-1750 3800);
PAINT ORANGE (-1750 3800);
DISPLAY INVISIBLE (-1750 3800);
FORCEPROP 2 LAST CDS_LOCATION C4M1
J 0
(-1750 3750);
DISPLAY 0.617021 (-1750 3750);
PAINT AQUA (-1750 3750);
DISPLAY INVISIBLE (-1750 3750);
FORCEPROP 2 LAST SEC 1
J 0
(-1750 3850);
DISPLAY 0.680851 (-1750 3850);
PAINT MONO (-1750 3850);
DISPLAY INVISIBLE (-1750 3850);
FORCEPROP 2 LAST SEC_TYPE 7343
J 0
(-1750 3850);
DISPLAY 1.021277 (-1750 3850);
PAINT ORANGE (-1750 3850);
DISPLAY INVISIBLE (-1750 3850);
FORCEADD RES..2
(-1375 2625);
FORCEPROP 1 LAST MATERIAL CHIP
J 0
(-1335 2500);
DISPLAY 0.617021 (-1335 2500);
PAINT SKYBLUE (-1335 2500);
FORCEPROP 1 LAST PART_NUMBER G85996-004
J 0
(-1360 2450);
DISPLAY 0.617021 (-1360 2450);
PAINT BLUE (-1360 2450);
FORCEPROP 1 LASTPIN (-1375 2525) $PN 2
J 0
(-1370 2535);
DISPLAY 0.617021 (-1370 2535);
PAINT ORANGE (-1370 2535);
FORCEPROP 1 LAST PACK_TYPE 0402
J 0
(-1335 2550);
DISPLAY 0.617021 (-1335 2550);
PAINT SKYBLUE (-1335 2550);
FORCEPROP 1 LASTPIN (-1375 2725) $PN 1
J 0
(-1370 2687);
DISPLAY 0.617021 (-1370 2687);
PAINT ORANGE (-1370 2687);
FORCEPROP 1 LAST WATTAGE 1/16W
J 0
(-1335 2600);
DISPLAY 0.617021 (-1335 2600);
PAINT SKYBLUE (-1335 2600);
FORCEPROP 1 LAST TOLERANCE 0.1%
J 0
(-1330 2650);
DISPLAY 0.617021 (-1330 2650);
PAINT SKYBLUE (-1330 2650);
FORCEPROP 1 LAST VALUE 1.0K
J 0
(-1330 2700);
DISPLAY 0.617021 (-1330 2700);
PAINT SKYBLUE (-1330 2700);
FORCEPROP 1 LAST LOCATION R7B18
J 0
(-1330 2750);
DISPLAY 0.617021 (-1330 2750);
PAINT AQUA (-1330 2750);
FORCEPROP 2 LAST CDS_LIB mstr_discrete
J 0
(-1375 2625);
PAINT MONO (-1375 2625);
DISPLAY INVISIBLE (-1375 2625);
FORCEPROP 2 LAST CDS_LOCATION R7B18
J 0
(-1330 2750);
DISPLAY 0.617021 (-1330 2750);
PAINT AQUA (-1330 2750);
DISPLAY INVISIBLE (-1330 2750);
FORCEPROP 2 LAST BOM_COST PVPP_KLM_VR
J 0
(-1330 2805);
DISPLAY 1.042553 (-1330 2805);
PAINT WHITE (-1330 2805);
DISPLAY INVISIBLE (-1330 2805);
FORCEPROP 1 LAST PATH I298
J 0
(-1325 2800);
DISPLAY 0.978723 (-1325 2800);
PAINT WHITE (-1325 2800);
DISPLAY INVISIBLE (-1325 2800);
FORCEPROP 2 LAST ROOM PVPP_KLM_VR
J 0
(-1330 2780);
PAINT GREEN (-1330 2780);
DISPLAY INVISIBLE (-1330 2780);
FORCEPROP 2 LAST SEC 1
J 0
(-1325 2850);
DISPLAY 0.680851 (-1325 2850);
PAINT MONO (-1325 2850);
DISPLAY INVISIBLE (-1325 2850);
FORCEPROP 2 LAST REUSE_ID 9
J 0
(-1325 2850);
DISPLAY 1.042553 (-1325 2850);
PAINT ORANGE (-1325 2850);
DISPLAY INVISIBLE (-1325 2850);
FORCEPROP 0 LAST SPOF TRUE
J 0
(-1325 2850);
DISPLAY 1.021277 (-1325 2850);
PAINT ORANGE (-1325 2850);
DISPLAY INVISIBLE (-1325 2850);
FORCEPROP 2 LAST SEC_TYPE 0402
J 0
(-1325 2850);
DISPLAY 1.021277 (-1325 2850);
PAINT ORANGE (-1325 2850);
DISPLAY INVISIBLE (-1325 2850);
FORCEADD RES..1
R 5
(-1700 2925);
FORCEPROP 1 LAST PACK_TYPE 0402
J 0
(-1675 2775);
DISPLAY 0.617021 (-1675 2775);
PAINT SKYBLUE (-1675 2775);
FORCEPROP 1 LASTPIN (-1700 3025) $PN 1
J 0
(-1688 3013);
DISPLAY 0.617021 (-1688 3013);
PAINT ORANGE (-1688 3013);
FORCEPROP 1 LASTPIN (-1700 2825) $PN 2
J 0
(-1688 2863);
DISPLAY 0.617021 (-1688 2863);
PAINT ORANGE (-1688 2863);
FORCEPROP 1 LAST TOLERANCE 5%
J 0
(-1675 2875);
DISPLAY 0.617021 (-1675 2875);
PAINT SKYBLUE (-1675 2875);
FORCEPROP 1 LAST MATERIAL CHIP
J 0
(-1675 2825);
DISPLAY 0.617021 (-1675 2825);
PAINT SKYBLUE (-1675 2825);
FORCEPROP 1 LAST VALUE 0.0
J 0
(-1650 2975);
DISPLAY 0.617021 (-1650 2975);
PAINT SKYBLUE (-1650 2975);
FORCEPROP 1 LAST WATTAGE 1/16W
J 0
(-1675 2925);
DISPLAY 0.617021 (-1675 2925);
PAINT SKYBLUE (-1675 2925);
FORCEPROP 1 LAST PART_NUMBER G21497-005
J 0
(-1675 2725);
DISPLAY 0.617021 (-1675 2725);
PAINT BLUE (-1675 2725);
FORCEPROP 1 LAST LOCATION R7B11
J 0
(-1600 2875);
DISPLAY 0.617021 (-1600 2875);
PAINT AQUA (-1600 2875);
FORCEPROP 2 LAST CDS_LIB mstr_discrete
J 0
(-1700 2925);
PAINT ORANGE (-1700 2925);
DISPLAY INVISIBLE (-1700 2925);
FORCEPROP 2 LAST CDS_LOCATION R7B11
J 0
(-1600 2875);
DISPLAY 0.617021 (-1600 2875);
PAINT AQUA (-1600 2875);
DISPLAY INVISIBLE (-1600 2875);
FORCEPROP 2 LAST ROOM PVPP_KLM_VR
R 3
J 0
(-1550 2975);
DISPLAY 1.659574 (-1550 2975);
PAINT GREEN (-1550 2975);
DISPLAY INVISIBLE (-1550 2975);
FORCEPROP 1 LAST PATH I299
R 3
J 0
(-1550 2975);
DISPLAY 0.978723 (-1550 2975);
PAINT WHITE (-1550 2975);
DISPLAY INVISIBLE (-1550 2975);
FORCEPROP 2 LAST SEC_TYPE 0402
J 0
(-1625 3075);
DISPLAY 1.021277 (-1625 3075);
PAINT ORANGE (-1625 3075);
DISPLAY INVISIBLE (-1625 3075);
FORCEPROP 0 LAST SPOF TRUE
J 0
(-1650 3075);
DISPLAY 1.021277 (-1650 3075);
PAINT ORANGE (-1650 3075);
DISPLAY INVISIBLE (-1650 3075);
FORCEPROP 2 LAST SEC 1
J 0
(-1625 3075);
DISPLAY 0.680851 (-1625 3075);
PAINT MONO (-1625 3075);
DISPLAY INVISIBLE (-1625 3075);
FORCEADD RES..1
(-2500 2450);
FORCEPROP 1 LAST VALUE 7.87K
J 2
(-2600 2325);
DISPLAY 0.617021 (-2600 2325);
PAINT SKYBLUE (-2600 2325);
FORCEPROP 1 LASTPIN (-2600 2450) $PN 1
J 0
(-2588 2462);
DISPLAY 0.617021 (-2588 2462);
PAINT ORANGE (-2588 2462);
FORCEPROP 1 LAST WATTAGE 1/16W
J 2
(-2525 2275);
DISPLAY 0.617021 (-2525 2275);
PAINT SKYBLUE (-2525 2275);
FORCEPROP 1 LAST PART_NUMBER G21796-242
J 0
(-2650 2375);
DISPLAY 0.617021 (-2650 2375);
PAINT BLUE (-2650 2375);
FORCEPROP 1 LAST MATERIAL CHIP
J 0
(-2500 2275);
DISPLAY 0.617021 (-2500 2275);
PAINT SKYBLUE (-2500 2275);
FORCEPROP 1 LAST TOLERANCE 1.0%
J 0
(-2550 2325);
DISPLAY 0.617021 (-2550 2325);
PAINT SKYBLUE (-2550 2325);
FORCEPROP 1 LASTPIN (-2400 2450) $PN 2
J 0
(-2438 2462);
DISPLAY 0.617021 (-2438 2462);
PAINT ORANGE (-2438 2462);
FORCEPROP 1 LAST LOCATION R7B16
J 0
(-2550 2500);
DISPLAY 0.617021 (-2550 2500);
PAINT AQUA (-2550 2500);
FORCEPROP 1 LAST PACK_TYPE 0402
J 0
(-2450 2325);
DISPLAY 0.617021 (-2450 2325);
PAINT SKYBLUE (-2450 2325);
FORCEPROP 2 LAST BOM_COST PVPP_KLM_VR
J 0
(-2500 2450);
PAINT WHITE (-2500 2450);
DISPLAY INVISIBLE (-2500 2450);
FORCEPROP 2 LAST CDS_LIB mstr_discrete
J 0
(-2500 2450);
PAINT MONO (-2500 2450);
DISPLAY INVISIBLE (-2500 2450);
FORCEPROP 2 LAST CDS_LOCATION R7B16
J 0
(-2550 2500);
DISPLAY 0.617021 (-2550 2500);
PAINT AQUA (-2550 2500);
DISPLAY INVISIBLE (-2550 2500);
FORCEPROP 2 LAST ROOM PVPP_KLM_VR
J 0
(-2500 2450);
PAINT GREEN (-2500 2450);
DISPLAY INVISIBLE (-2500 2450);
FORCEPROP 0 LAST SEC 1
J 0
(-2550 2550);
PAINT MONO (-2550 2550);
DISPLAY INVISIBLE (-2550 2550);
FORCEPROP 2 LAST SEC_TYPE 0402
J 0
(-2550 2650);
DISPLAY 1.021277 (-2550 2650);
PAINT ORANGE (-2550 2650);
DISPLAY INVISIBLE (-2550 2650);
FORCEPROP 2 LAST REUSE_ID 13
J 0
(-2550 2650);
DISPLAY 1.042553 (-2550 2650);
PAINT ORANGE (-2550 2650);
DISPLAY INVISIBLE (-2550 2650);
FORCEPROP 1 LAST PATH I300
J 0
(-2550 2600);
DISPLAY 0.978723 (-2550 2600);
PAINT WHITE (-2550 2600);
DISPLAY INVISIBLE (-2550 2600);
FORCEADD CAP..2
R 2
(-2775 2825);
FORCEPROP 1 LAST PART_NUMBER A36095-026
J 1
(-3125 2725);
DISPLAY 0.617021 (-3125 2725);
PAINT BLUE (-3125 2725);
FORCEPROP 1 LASTPIN (-2875 2825) $PN 2
J 2
(-2860 2840);
DISPLAY 0.617021 (-2860 2840);
PAINT ORANGE (-2860 2840);
FORCEPROP 1 LAST PACK_TYPE 0402LF
J 1
(-2925 2725);
DISPLAY 0.617021 (-2925 2725);
PAINT SKYBLUE (-2925 2725);
FORCEPROP 1 LAST VOLTAGE 50V
J 2
(-2775 2725);
DISPLAY 0.617021 (-2775 2725);
PAINT SKYBLUE (-2775 2725);
FORCEPROP 1 LAST LOCATION C7B10
J 1
(-2775 2875);
DISPLAY 0.617021 (-2775 2875);
PAINT AQUA (-2775 2875);
FORCEPROP 1 LASTPIN (-2675 2825) $PN 1
J 2
(-2665 2840);
DISPLAY 0.617021 (-2665 2840);
PAINT ORANGE (-2665 2840);
FORCEPROP 1 LAST VALUE 100.0PF
J 0
(-2775 2725);
DISPLAY 0.617021 (-2775 2725);
PAINT SKYBLUE (-2775 2725);
FORCEPROP 1 LAST TOLERANCE 5%
J 0
(-2600 2725);
DISPLAY 0.617021 (-2600 2725);
PAINT SKYBLUE (-2600 2725);
FORCEPROP 1 LAST MATERIAL COG
J 2
(-2425 2725);
DISPLAY 0.617021 (-2425 2725);
PAINT SKYBLUE (-2425 2725);
FORCEPROP 2 LAST BOM_COST PVPP_KLM_VR
J 0
(-2820 2985);
DISPLAY 1.042553 (-2820 2985);
PAINT WHITE (-2820 2985);
DISPLAY INVISIBLE (-2820 2985);
FORCEPROP 1 LAST PATH I301
J 2
(-2775 3025);
DISPLAY 0.978723 (-2775 3025);
PAINT WHITE (-2775 3025);
DISPLAY INVISIBLE (-2775 3025);
FORCEPROP 2 LAST CDS_LIB mstr_discrete
J 0
(-2775 2825);
PAINT ORANGE (-2775 2825);
DISPLAY INVISIBLE (-2775 2825);
FORCEPROP 2 LAST CDS_LOCATION C7B10
J 1
(-2775 2875);
DISPLAY 0.617021 (-2775 2875);
PAINT AQUA (-2775 2875);
DISPLAY INVISIBLE (-2775 2875);
FORCEPROP 2 LAST ROOM PVPP_KLM_VR
J 2
(-2775 2950);
DISPLAY 0.765957 (-2775 2950);
PAINT GREEN (-2775 2950);
DISPLAY INVISIBLE (-2775 2950);
FORCEPROP 2 LAST SEC 1
J 0
(-2775 3075);
DISPLAY 0.680851 (-2775 3075);
PAINT MONO (-2775 3075);
DISPLAY INVISIBLE (-2775 3075);
FORCEPROP 2 LAST SEC_TYPE 0402LF
J 0
(-2775 3075);
DISPLAY 1.021277 (-2775 3075);
PAINT ORANGE (-2775 3075);
DISPLAY INVISIBLE (-2775 3075);
FORCEPROP 2 LAST REUSE_ID 27
J 0
(-2775 3075);
DISPLAY 1.042553 (-2775 3075);
PAINT ORANGE (-2775 3075);
DISPLAY INVISIBLE (-2775 3075);
FORCEADD CAP..1
(-1375 2075);
FORCEPROP 1 LASTPIN (-1375 1975) $PN 2
J 0
(-1365 1955);
DISPLAY 0.617021 (-1365 1955);
PAINT ORANGE (-1365 1955);
FORCEPROP 1 LAST MATERIAL X7R
J 0
(-1325 1975);
DISPLAY 0.617021 (-1325 1975);
PAINT SKYBLUE (-1325 1975);
FORCEPROP 1 LAST PACK_TYPE 0402LF
J 0
(-1325 1875);
DISPLAY 0.617021 (-1325 1875);
PAINT SKYBLUE (-1325 1875);
FORCEPROP 1 LAST PART_NUMBER A36096-075
J 0
(-1325 1925);
DISPLAY 0.617021 (-1325 1925);
PAINT BLUE (-1325 1925);
FORCEPROP 1 LAST TOLERANCE 10%
J 0
(-1325 2025);
DISPLAY 0.617021 (-1325 2025);
PAINT SKYBLUE (-1325 2025);
FORCEPROP 1 LASTPIN (-1375 2175) $PN 1
J 0
(-1365 2155);
DISPLAY 0.617021 (-1365 2155);
PAINT ORANGE (-1365 2155);
FORCEPROP 1 LAST VOLTAGE 50V
J 0
(-1325 2075);
DISPLAY 0.617021 (-1325 2075);
PAINT SKYBLUE (-1325 2075);
FORCEPROP 1 LAST VALUE 2200PF
J 0
(-1325 2125);
DISPLAY 0.617021 (-1325 2125);
PAINT SKYBLUE (-1325 2125);
FORCEPROP 1 LAST LOCATION C7B13
J 0
(-1325 2175);
DISPLAY 0.617021 (-1325 2175);
PAINT AQUA (-1325 2175);
FORCEPROP 2 LAST SEC 1
J 0
(-1325 2275);
DISPLAY 0.680851 (-1325 2275);
PAINT MONO (-1325 2275);
DISPLAY INVISIBLE (-1325 2275);
FORCEPROP 2 LAST CDS_LIB mstr_discrete
J 0
(-1375 2075);
PAINT ORANGE (-1375 2075);
DISPLAY INVISIBLE (-1375 2075);
FORCEPROP 2 LAST BOM_COST PVPP_KLM_VR
J 0
(-1325 2225);
DISPLAY 1.042553 (-1325 2225);
PAINT WHITE (-1325 2225);
DISPLAY INVISIBLE (-1325 2225);
FORCEPROP 2 LAST CDS_LOCATION C7B13
J 0
(-1325 2175);
DISPLAY 0.617021 (-1325 2175);
PAINT AQUA (-1325 2175);
DISPLAY INVISIBLE (-1325 2175);
FORCEPROP 1 LAST PATH I302
J 0
(-1325 2225);
DISPLAY 0.978723 (-1325 2225);
PAINT WHITE (-1325 2225);
DISPLAY INVISIBLE (-1325 2225);
FORCEPROP 2 LAST ROOM PVPP_KLM_VR
J 0
(-1325 2200);
PAINT GREEN (-1325 2200);
DISPLAY INVISIBLE (-1325 2200);
FORCEPROP 2 LAST REUSE_ID 26
J 0
(-1325 2275);
DISPLAY 1.042553 (-1325 2275);
PAINT ORANGE (-1325 2275);
DISPLAY INVISIBLE (-1325 2275);
FORCEPROP 2 LAST SEC_TYPE 0402LF
J 0
(-1325 2275);
DISPLAY 1.021277 (-1325 2275);
PAINT ORANGE (-1325 2275);
DISPLAY INVISIBLE (-1325 2275);
FORCEPROP 0 LAST SPOF TRUE
J 0
(-1325 2275);
DISPLAY 1.021277 (-1325 2275);
PAINT ORANGE (-1325 2275);
DISPLAY INVISIBLE (-1325 2275);
FORCEADD RES..2
(-1700 2175);
FORCEPROP 1 LAST PART_NUMBER G21796-040
J 0
(-1685 2000);
DISPLAY 0.617021 (-1685 2000);
PAINT BLUE (-1685 2000);
FORCEPROP 1 LASTPIN (-1700 2075) $PN 2
J 0
(-1695 2085);
DISPLAY 0.617021 (-1695 2085);
PAINT WHITE (-1695 2085);
FORCEPROP 1 LASTPIN (-1700 2275) $PN 1
J 0
(-1695 2237);
DISPLAY 0.617021 (-1695 2237);
PAINT WHITE (-1695 2237);
FORCEPROP 1 LAST MATERIAL CHIP
J 0
(-1660 2050);
DISPLAY 0.617021 (-1660 2050);
PAINT SKYBLUE (-1660 2050);
FORCEPROP 1 LAST PACK_TYPE 0402
J 0
(-1660 2100);
DISPLAY 0.617021 (-1660 2100);
PAINT SKYBLUE (-1660 2100);
FORCEPROP 1 LAST TOLERANCE 1%
J 0
(-1655 2200);
DISPLAY 0.617021 (-1655 2200);
PAINT SKYBLUE (-1655 2200);
FORCEPROP 1 LAST WATTAGE 1/16W
J 0
(-1660 2150);
DISPLAY 0.617021 (-1660 2150);
PAINT SKYBLUE (-1660 2150);
FORCEPROP 1 LAST VALUE 20.0K
J 0
(-1655 2250);
DISPLAY 0.617021 (-1655 2250);
PAINT SKYBLUE (-1655 2250);
FORCEPROP 1 LAST LOCATION R7B15
J 0
(-1655 2300);
DISPLAY 0.617021 (-1655 2300);
PAINT AQUA (-1655 2300);
FORCEPROP 2 LAST CDS_LIB mstr_discrete
J 0
(-1700 2175);
PAINT MONO (-1700 2175);
DISPLAY INVISIBLE (-1700 2175);
FORCEPROP 2 LAST CDS_LOCATION R7B15
J 0
(-1655 2300);
DISPLAY 0.617021 (-1655 2300);
PAINT AQUA (-1655 2300);
DISPLAY INVISIBLE (-1655 2300);
FORCEPROP 0 LAST SPOF TRUE
J 0
(-1650 2400);
DISPLAY 1.021277 (-1650 2400);
PAINT ORANGE (-1650 2400);
DISPLAY INVISIBLE (-1650 2400);
FORCEPROP 2 LAST CDS_SEC 1
J 0
(-1650 2400);
DISPLAY 1.042553 (-1650 2400);
PAINT ORANGE (-1650 2400);
DISPLAY INVISIBLE (-1650 2400);
FORCEPROP 2 LAST ROOM PVPP_KLM_VR
J 0
(-1655 2330);
PAINT GREEN (-1655 2330);
DISPLAY INVISIBLE (-1655 2330);
FORCEPROP 1 LAST PATH I303
J 0
(-1650 2350);
DISPLAY 0.978723 (-1650 2350);
PAINT WHITE (-1650 2350);
DISPLAY INVISIBLE (-1650 2350);
FORCEPROP 2 LAST REUSE_ID 9
J 0
(-1650 2400);
DISPLAY 1.042553 (-1650 2400);
PAINT ORANGE (-1650 2400);
DISPLAY INVISIBLE (-1650 2400);
FORCEPROP 2 LAST BOM_COST PVPP_KLM_VR
J 0
(-1655 2355);
DISPLAY 1.042553 (-1655 2355);
PAINT WHITE (-1655 2355);
DISPLAY INVISIBLE (-1655 2355);
FORCEPROP 2 LAST $SEC 1
J 0
(-1650 2400);
DISPLAY 0.680851 (-1650 2400);
PAINT MONO (-1650 2400);
DISPLAY INVISIBLE (-1650 2400);
FORCEADD RES..2
(-1700 1550);
FORCEPROP 1 LASTPIN (-1700 1450) $PN 2
J 0
(-1695 1460);
DISPLAY 0.617021 (-1695 1460);
PAINT WHITE (-1695 1460);
FORCEPROP 1 LAST MATERIAL CHIP
J 0
(-1660 1475);
DISPLAY 0.617021 (-1660 1475);
PAINT SKYBLUE (-1660 1475);
FORCEPROP 1 LAST PACK_TYPE 0402
J 0
(-1660 1375);
DISPLAY 0.617021 (-1660 1375);
PAINT SKYBLUE (-1660 1375);
FORCEPROP 1 LASTPIN (-1700 1650) $PN 1
J 0
(-1695 1612);
DISPLAY 0.617021 (-1695 1612);
PAINT WHITE (-1695 1612);
FORCEPROP 1 LAST TOLERANCE 1%
J 0
(-1655 1575);
DISPLAY 0.617021 (-1655 1575);
PAINT SKYBLUE (-1655 1575);
FORCEPROP 1 LAST WATTAGE 1/16W
J 0
(-1660 1525);
DISPLAY 0.617021 (-1660 1525);
PAINT SKYBLUE (-1660 1525);
FORCEPROP 1 LAST VALUE 6.34K
J 0
(-1655 1625);
DISPLAY 0.617021 (-1655 1625);
PAINT SKYBLUE (-1655 1625);
FORCEPROP 1 LAST PART_NUMBER G21796-146
J 0
(-1660 1425);
DISPLAY 0.617021 (-1660 1425);
PAINT BLUE (-1660 1425);
FORCEPROP 1 LAST LOCATION R7B13
J 0
(-1655 1675);
DISPLAY 0.617021 (-1655 1675);
PAINT AQUA (-1655 1675);
FORCEPROP 2 LAST BOM_COST PVPP_KLM_VR
R 1
J 0
(-2000 1600);
DISPLAY 1.042553 (-2000 1600);
PAINT WHITE (-2000 1600);
DISPLAY INVISIBLE (-2000 1600);
FORCEPROP 2 LAST ROOM PVPP_KLM_VR
R 1
J 0
(-1900 1600);
DISPLAY 1.042553 (-1900 1600);
PAINT GREEN (-1900 1600);
DISPLAY INVISIBLE (-1900 1600);
FORCEPROP 2 LAST CDS_LIB mstr_discrete
R 1
J 0
(-1700 1550);
PAINT MONO (-1700 1550);
DISPLAY INVISIBLE (-1700 1550);
FORCEPROP 2 LAST CDS_LOCATION R7B13
J 0
(-1655 1675);
DISPLAY 0.617021 (-1655 1675);
PAINT AQUA (-1655 1675);
DISPLAY INVISIBLE (-1655 1675);
FORCEPROP 1 LAST PATH I304
J 0
(-1650 1725);
DISPLAY 0.978723 (-1650 1725);
PAINT WHITE (-1650 1725);
DISPLAY INVISIBLE (-1650 1725);
FORCEPROP 2 LAST $SEC 1
J 0
(-1650 1775);
DISPLAY 0.680851 (-1650 1775);
PAINT MONO (-1650 1775);
DISPLAY INVISIBLE (-1650 1775);
FORCEPROP 2 LAST REUSE_ID 7
J 0
(-1650 1775);
DISPLAY 1.042553 (-1650 1775);
PAINT ORANGE (-1650 1775);
DISPLAY INVISIBLE (-1650 1775);
FORCEPROP 0 LAST SPOF TRUE
J 0
(-1650 1775);
DISPLAY 1.021277 (-1650 1775);
PAINT ORANGE (-1650 1775);
DISPLAY INVISIBLE (-1650 1775);
FORCEPROP 2 LAST CDS_SEC 1
J 0
(-1650 1775);
DISPLAY 1.042553 (-1650 1775);
PAINT ORANGE (-1650 1775);
DISPLAY INVISIBLE (-1650 1775);
FORCEADD CAP..2
R 2
(-3200 2450);
FORCEPROP 1 LAST PACK_TYPE 0402LF
J 1
(-3200 2250);
DISPLAY 0.617021 (-3200 2250);
PAINT SKYBLUE (-3200 2250);
FORCEPROP 1 LAST TOLERANCE 10%
J 0
(-3200 2300);
DISPLAY 0.617021 (-3200 2300);
PAINT SKYBLUE (-3200 2300);
FORCEPROP 1 LAST MATERIAL X7R
J 2
(-3200 2300);
DISPLAY 0.617021 (-3200 2300);
PAINT SKYBLUE (-3200 2300);
FORCEPROP 1 LAST LOCATION C7B14
J 1
(-3200 2525);
DISPLAY 0.617021 (-3200 2525);
PAINT AQUA (-3200 2525);
FORCEPROP 1 LAST VOLTAGE 50V
J 2
(-3200 2350);
DISPLAY 0.617021 (-3200 2350);
PAINT SKYBLUE (-3200 2350);
FORCEPROP 1 LASTPIN (-3300 2450) $PN 2
J 2
(-3285 2465);
DISPLAY 0.617021 (-3285 2465);
PAINT ORANGE (-3285 2465);
FORCEPROP 1 LASTPIN (-3100 2450) $PN 1
J 2
(-3090 2465);
DISPLAY 0.617021 (-3090 2465);
PAINT ORANGE (-3090 2465);
FORCEPROP 1 LAST VALUE 2200PF
J 0
(-3200 2350);
DISPLAY 0.617021 (-3200 2350);
PAINT SKYBLUE (-3200 2350);
FORCEPROP 1 LAST PART_NUMBER A36096-075
J 1
(-3150 2200);
DISPLAY 0.617021 (-3150 2200);
PAINT BLUE (-3150 2200);
FORCEPROP 2 LAST CDS_LIB mstr_discrete
J 0
(-3200 2450);
PAINT ORANGE (-3200 2450);
DISPLAY INVISIBLE (-3200 2450);
FORCEPROP 2 LAST CDS_LOCATION C7B14
J 1
(-3200 2525);
DISPLAY 0.617021 (-3200 2525);
PAINT AQUA (-3200 2525);
DISPLAY INVISIBLE (-3200 2525);
FORCEPROP 2 LAST SEC_TYPE 0402LF
J 0
(-3200 2700);
DISPLAY 1.021277 (-3200 2700);
PAINT ORANGE (-3200 2700);
DISPLAY INVISIBLE (-3200 2700);
FORCEPROP 2 LAST BOM_COST PVPP_KLM_VR
J 0
(-3245 2610);
DISPLAY 1.042553 (-3245 2610);
PAINT WHITE (-3245 2610);
DISPLAY INVISIBLE (-3245 2610);
FORCEPROP 2 LAST REUSE_ID 27
J 0
(-3200 2700);
DISPLAY 1.042553 (-3200 2700);
PAINT ORANGE (-3200 2700);
DISPLAY INVISIBLE (-3200 2700);
FORCEPROP 2 LAST SEC 1
J 0
(-3200 2700);
DISPLAY 0.680851 (-3200 2700);
PAINT MONO (-3200 2700);
DISPLAY INVISIBLE (-3200 2700);
FORCEPROP 1 LAST PATH I306
J 2
(-3200 2650);
DISPLAY 0.978723 (-3200 2650);
PAINT WHITE (-3200 2650);
DISPLAY INVISIBLE (-3200 2650);
FORCEPROP 2 LAST ROOM PVPP_KLM_VR
J 2
(-3200 2575);
DISPLAY 0.765957 (-3200 2575);
PAINT GREEN (-3200 2575);
DISPLAY INVISIBLE (-3200 2575);
FORCEADD RES..1
(-6500 2825);
FORCEPROP 1 LAST WATTAGE 1/16W
J 2
(-6525 2675);
DISPLAY 0.617021 (-6525 2675);
PAINT SKYBLUE (-6525 2675);
FORCEPROP 1 LAST VALUE 0.0
J 2
(-6600 2725);
DISPLAY 0.617021 (-6600 2725);
PAINT SKYBLUE (-6600 2725);
FORCEPROP 1 LAST TOLERANCE 5%
J 0
(-6550 2725);
DISPLAY 0.617021 (-6550 2725);
PAINT SKYBLUE (-6550 2725);
FORCEPROP 1 LASTPIN (-6600 2825) $PN 1
J 0
(-6588 2837);
DISPLAY 0.617021 (-6588 2837);
PAINT ORANGE (-6588 2837);
FORCEPROP 1 LASTPIN (-6400 2825) $PN 2
J 0
(-6438 2837);
DISPLAY 0.617021 (-6438 2837);
PAINT ORANGE (-6438 2837);
FORCEPROP 1 LAST LOCATION R7B9
J 0
(-6550 2875);
DISPLAY 0.617021 (-6550 2875);
PAINT AQUA (-6550 2875);
FORCEPROP 1 LAST MATERIAL CHIP
J 0
(-6500 2675);
DISPLAY 0.617021 (-6500 2675);
PAINT SKYBLUE (-6500 2675);
FORCEPROP 1 LAST PACK_TYPE 0402
J 0
(-6425 2725);
DISPLAY 0.617021 (-6425 2725);
PAINT SKYBLUE (-6425 2725);
FORCEPROP 1 LAST PART_NUMBER G21497-005
J 0
(-6650 2775);
DISPLAY 0.617021 (-6650 2775);
PAINT BLUE (-6650 2775);
FORCEPROP 2 LAST SEC_TYPE 0402
J 0
(-6550 3025);
DISPLAY 1.021277 (-6550 3025);
PAINT ORANGE (-6550 3025);
DISPLAY INVISIBLE (-6550 3025);
FORCEPROP 2 LAST CDS_LIB mstr_discrete
J 0
(-6500 2825);
PAINT ORANGE (-6500 2825);
DISPLAY INVISIBLE (-6500 2825);
FORCEPROP 2 LAST SEC 1
J 0
(-6550 3025);
PAINT MONO (-6550 3025);
DISPLAY INVISIBLE (-6550 3025);
FORCEPROP 2 LAST CDS_LOCATION R7B9
J 0
(-6550 2875);
DISPLAY 0.617021 (-6550 2875);
PAINT AQUA (-6550 2875);
DISPLAY INVISIBLE (-6550 2875);
FORCEPROP 1 LAST PATH I307
J 0
(-6550 2975);
DISPLAY 0.978723 (-6550 2975);
PAINT WHITE (-6550 2975);
DISPLAY INVISIBLE (-6550 2975);
FORCEPROP 2 LAST ROOM PVCCIN_CPU0_VR
J 0
(-6550 2925);
DISPLAY 1.361702 (-6550 2925);
PAINT ORANGE (-6550 2925);
DISPLAY INVISIBLE (-6550 2925);
FORCEADD AGND_SCSI..1
(-1700 1175);
FORCEPROP 3 LASTPIN (-1700 1225) SIG_NAME AGND_PVPP_DEF\g
J 0
(-1690 1235);
DISPLAY 0.659574 (-1690 1235);
PAINT MONO (-1690 1235);
DISPLAY INVISIBLE (-1690 1235);
FORCEPROP 1 LAST HDL_POWER AGND_PVPP_DEF
J 1
(-1625 1100);
DISPLAY 0.617021 (-1625 1100);
PAINT GREEN (-1625 1100);
FORCEPROP 2 LAST BOM_COST PVPP_KLM_VR
J 0
(-1850 1125);
DISPLAY 1.042553 (-1850 1125);
PAINT WHITE (-1850 1125);
DISPLAY INVISIBLE (-1850 1125);
FORCEPROP 2 LAST ROOM PVPP_KLM_VR
J 0
(-1850 1125);
DISPLAY 1.042553 (-1850 1125);
PAINT GREEN (-1850 1125);
DISPLAY INVISIBLE (-1850 1125);
FORCEPROP 1 LAST VOLTAGE 0.0V
J 0
(-1745 1132);
DISPLAY 0.340426 (-1745 1132);
PAINT SKYBLUE (-1745 1132);
DISPLAY INVISIBLE (-1745 1132);
FORCEPROP 1 LAST PATH I308
J 0
(-1625 1175);
DISPLAY 0.872340 (-1625 1175);
PAINT AQUA (-1625 1175);
DISPLAY INVISIBLE (-1625 1175);
FORCEPROP 1 LAST BODY_TYPE PLUMBING
J 0
(-1745 1132);
DISPLAY 0.340426 (-1745 1132);
PAINT GREEN (-1745 1132);
DISPLAY INVISIBLE (-1745 1132);
FORCEPROP 2 LAST CDS_LIB mstr_symbols
J 0
(-1700 1175);
PAINT ORANGE (-1700 1175);
DISPLAY INVISIBLE (-1700 1175);
FORCEADD DNS..2
(-2995 3345);
PAINT RED (-2995 3345);
FORCEPROP 1 LAST COMMENT_BODY TRUE
R 1
J 0
(-2920 3120);
DISPLAY 0.872340 (-2920 3120);
PAINT GREEN (-2920 3120);
DISPLAY INVISIBLE (-2920 3120);
FORCEPROP 2 LAST CDS_LIB mstr_misc
J 0
(-2995 3345);
PAINT ORANGE (-2995 3345);
DISPLAY INVISIBLE (-2995 3345);
FORCEADD DNS..2
(-2995 3695);
PAINT RED (-2995 3695);
FORCEPROP 1 LAST COMMENT_BODY TRUE
R 1
J 0
(-2920 3470);
DISPLAY 0.872340 (-2920 3470);
PAINT GREEN (-2920 3470);
DISPLAY INVISIBLE (-2920 3470);
FORCEPROP 2 LAST CDS_LIB mstr_misc
J 0
(-2995 3695);
PAINT ORANGE (-2995 3695);
DISPLAY INVISIBLE (-2995 3695);
FORCEADD DNS..2
(-6820 2495);
PAINT RED (-6820 2495);
FORCEPROP 1 LAST COMMENT_BODY TRUE
R 1
J 0
(-6745 2270);
DISPLAY 0.872340 (-6745 2270);
PAINT GREEN (-6745 2270);
DISPLAY INVISIBLE (-6745 2270);
FORCEPROP 2 LAST CDS_LIB mstr_misc
J 0
(-6820 2495);
PAINT ORANGE (-6820 2495);
DISPLAY INVISIBLE (-6820 2495);
FORCEADD INTEL_CORP_BPAGE..1
(-800 50);
FORCEPROP 1 LAST CDS_CON_LAST_MODIFIED Tue Dec 01 11:52:29 2015
J 0
(-2225 375);
DISPLAY 0.659574 (-2225 375);
PAINT GREEN (-2225 375);
DISPLAY INVISIBLE (-2225 375);
FORCEPROP 1 LAST CUSTOM_TXT_CDS <CURRENT_DESIGN_SHEET> OF <TOTAL_DESIGN_SHEETS>
J 0
(-1300 75);
PAINT GREEN (-1300 75);
FORCEPROP 2 LAST CUSTOM_TXT_CDS <XR_PAGE_TITLE>
J 0
(-8690 5300);
DISPLAY 0.638298 (-8690 5300);
PAINT PINK (-8690 5300);
DISPLAY INVISIBLE (-8690 5300);
FORCEPROP 2 LAST CUSTOM_TXT_CDS <CON_LAST_MODIFIED>
J 0
(-2725 400);
DISPLAY 0.957447 (-2725 400);
PAINT ORANGE (-2725 400);
FORCEPROP 1 LAST SCH_TITLE VPP DEF VR
J 0
(-8750 100);
DISPLAY 1.212766 (-8750 100);
PAINT GREEN (-8750 100);
FORCEPROP 1 LAST SCH_ADDRESS2 P.O. BOX 58119
J 0
(-4775 125);
DISPLAY 0.617021 (-4775 125);
PAINT GREEN (-4775 125);
FORCEPROP 1 LAST SCH_ADDRESS1 2200 Mission College Blvd.
J 0
(-4775 175);
DISPLAY 0.617021 (-4775 175);
PAINT GREEN (-4775 175);
FORCEPROP 1 LAST SCH_ADDRESS3 Santa Clara, CA 95052-8119
J 0
(-4775 75);
DISPLAY 0.617021 (-4775 75);
PAINT GREEN (-4775 75);
FORCEPROP 1 LAST SCH_NUMBER H4694802
J 0
(-2100 200);
DISPLAY 1.212766 (-2100 200);
PAINT YELLOW (-2100 200);
FORCEPROP 1 LAST SCH_DEPT BESD
J 1
(-5250 150);
DISPLAY 1.212766 (-5250 150);
PAINT YELLOW (-5250 150);
FORCEPROP 1 LAST SCH_REV 2.420
J 0
(-1050 200);
DISPLAY 0.978723 (-1050 200);
PAINT YELLOW (-1050 200);
FORCEPROP 2 LAST PAGE_BORDER TRUE
J 0
(-8690 5300);
DISPLAY 0.425532 (-8690 5300);
PAINT PINK (-8690 5300);
DISPLAY INVISIBLE (-8690 5300);
FORCEPROP 1 LAST COMMENT_BODY TRUE
J 0
(-788 62);
DISPLAY 0.319149 (-788 62);
PAINT GREEN (-788 62);
DISPLAY INVISIBLE (-788 62);
FORCEPROP 2 LAST CDS_LIB mstr_symbols
J 0
(-800 50);
DISPLAY 0.489362 (-800 50);
PAINT ORANGE (-800 50);
DISPLAY INVISIBLE (-800 50);
FORCEPROP 2 LAST CDS_XR_PAGE_TITLE CR-232 : @BASEBOARD_FAB2_LIB.BASEBOARD_FAB2(SCH_1):PAGE232
J 0
(-8690 5300);
DISPLAY 0.638298 (-8690 5300);
PAINT PINK (-8690 5300);
DISPLAY INVISIBLE (-8690 5300);
WIRE 16 -1 (-5525 975)(-5525 1050);
WIRE 16 -1 (-5525 1050)(-5775 1050);
WIRE 16 -1 (-5775 950)(-5775 1050);
WIRE 16 -1 (-5775 1050)(-6050 1050);
WIRE 16 -1 (-6050 950)(-6050 1050);
WIRE 16 -1 (-6050 1050)(-6325 1050);
WIRE 16 -1 (-6325 975)(-6325 1050);
WIRE 16 -1 (-6325 1050)(-6625 1050);
WIRE 16 -1 (-6625 975)(-6625 1050);
WIRE 16 -1 (-6625 1050)(-6925 1050);
WIRE 16 -1 (-6925 1050)(-6925 975);
WIRE 16 -1 (-6925 1050)(-7200 1050);
WIRE 16 -1 (-7200 975)(-7200 1050);
WIRE 16 -1 (-7200 1050)(-7500 1050);
WIRE 16 -1 (-7500 975)(-7500 1050);
WIRE 16 -1 (-7500 1050)(-7775 1050);
WIRE 16 -1 (-7775 950)(-7775 1050);
WIRE 16 -1 (-7775 1050)(-8025 1050);
WIRE 16 -1 (-8025 975)(-8025 1050);
WIRE 16 -1 (-8025 1050)(-8300 1050);
WIRE 16 -1 (-8300 975)(-8300 1050);
WIRE 16 -1 (-8550 1050)(-8300 1050);
WIRE 16 -1 (-8550 1050)(-8550 1100);
WIRE 16 -1 (-8550 1050)(-8550 975);
WIRE 16 -1 (-8550 775)(-8550 625);
WIRE 16 -1 (-8550 625)(-8300 625);
WIRE 16 -1 (-8300 775)(-8300 625);
WIRE 16 -1 (-8025 625)(-8300 625);
WIRE 16 -1 (-8025 775)(-8025 625);
WIRE 16 -1 (-7775 625)(-8025 625);
WIRE 16 -1 (-7775 750)(-7775 625);
WIRE 16 -1 (-7500 625)(-7775 625);
WIRE 16 -1 (-7500 775)(-7500 625);
WIRE 16 -1 (-7200 625)(-7500 625);
WIRE 16 -1 (-7200 775)(-7200 625);
WIRE 16 -1 (-6925 625)(-7200 625);
WIRE 16 -1 (-6925 775)(-6925 625);
WIRE 16 -1 (-6625 625)(-6925 625);
WIRE 16 -1 (-6625 775)(-6625 625);
WIRE 16 -1 (-6325 625)(-6625 625);
WIRE 16 -1 (-6325 775)(-6325 625);
WIRE 16 -1 (-6050 625)(-6325 625);
WIRE 16 -1 (-6050 750)(-6050 625);
WIRE 16 -1 (-5775 625)(-6050 625);
WIRE 16 -1 (-5775 750)(-5775 625);
WIRE 16 -1 (-5600 625)(-5775 625);
WIRE 16 -1 (-5600 625)(-5525 625);
WIRE 16 -1 (-5600 625)(-5600 600);
WIRE 16 -1 (-5525 775)(-5525 625);
WIRE 16 -1 (-1875 775)(-1675 775);
WIRE 16 -1 (-1875 725)(-1875 775);
WIRE 16 -1 (-1325 775)(-1475 775);
WIRE 16 -1 (-1325 725)(-1325 775);
WIRE 16 -1 (-2550 3850)(-2425 3850);
WIRE 16 -1 (-2425 3850)(-2075 3850);
WIRE 16 -1 (-2425 3775)(-2425 3850);
WIRE 16 -1 (-2075 3850)(-1800 3850);
WIRE 16 -1 (-2075 3850)(-2075 3775);
WIRE 16 -1 (-1800 3750)(-1800 3850);
WIRE 16 -1 (-1800 3850)(-1475 3850);
WIRE 16 -1 (-1475 3850)(-1200 3850);
WIRE 16 -1 (-1475 3850)(-1475 3775);
WIRE 16 -1 (-1150 3850)(-1200 3850);
WIRE 16 -1 (-1200 3850)(-1200 3775);
WIRE 16 -1 (-950 3850)(-1150 3850);
WIRE 16 -1 (-1150 3925)(-1150 3850);
WIRE 16 -1 (-950 3850)(-950 3175);
WIRE 16 -1 (-1700 3175)(-950 3175);
WIRE 16 -1 (-1700 3175)(-1700 3025);
WIRE 16 -1 (-5300 3875)(-5300 4050);
WIRE 16 -1 (-7950 4300)(-7825 4300);
WIRE 16 -1 (-7950 4450)(-7950 4300);
WIRE 16 -1 (-7375 3950)(-7375 4025);
WIRE 16 -1 (-4225 625)(-4225 525);
WIRE 16 -1 (-4575 1475)(-4575 1350);
WIRE 16 -1 (-3650 2725)(-3425 2725);
WIRE 16 -1 (-3425 2725)(-3425 2675);
WIRE 16 -1 (-3650 2675)(-3425 2675);
WIRE 16 -1 (-3425 2675)(-3425 2625);
WIRE 16 -1 (-3650 2625)(-3425 2625);
WIRE 16 -1 (-3425 2625)(-3425 2575);
WIRE 16 -1 (-3650 2575)(-3425 2575);
WIRE 16 -1 (-3425 2575)(-3425 2525);
WIRE 16 -1 (-3650 2525)(-3425 2525);
WIRE 16 -1 (-3425 2525)(-3425 2475);
WIRE 16 -1 (-3650 2475)(-3425 2475);
WIRE 16 -1 (-3425 2475)(-3425 2425);
WIRE 16 -1 (-3650 2425)(-3425 2425);
WIRE 16 -1 (-3425 2425)(-3425 2375);
WIRE 16 -1 (-3650 2375)(-3425 2375);
WIRE 16 -1 (-3425 2375)(-3425 2325);
WIRE 16 -1 (-3650 2325)(-3425 2325);
WIRE 16 -1 (-3425 2325)(-3425 2275);
WIRE 16 -1 (-3650 2275)(-3425 2275);
WIRE 16 -1 (-3425 2275)(-3425 2225);
WIRE 16 -1 (-3650 2225)(-3425 2225);
WIRE 16 -1 (-3425 2225)(-3425 2175);
WIRE 16 -1 (-3650 2175)(-3425 2175);
WIRE 16 -1 (-3425 2175)(-3425 2125);
WIRE 16 -1 (-3650 2125)(-3425 2125);
WIRE 16 -1 (-3425 2125)(-3425 2075);
WIRE 16 -1 (-3650 2075)(-3425 2075);
WIRE 16 -1 (-3425 2075)(-3425 2025);
WIRE 16 -1 (-3650 2025)(-3425 2025);
WIRE 16 -1 (-3425 2025)(-3425 1975);
WIRE 16 -1 (-3000 3250)(-3000 3200);
WIRE 16 -1 (-2425 3475)(-2425 3575);
WIRE 16 -1 (-1800 3550)(-1800 3450);
WIRE 16 -1 (-1800 3450)(-2075 3450);
WIRE 16 -1 (-2075 3450)(-2075 3575);
WIRE 16 -1 (-2075 3425)(-2075 3450);
WIRE 16 -1 (-1475 3475)(-1475 3575);
WIRE 16 -1 (-1200 3450)(-1200 3575);
WIRE 16 -1 (-6125 2075)(-6125 2325);
WIRE 16 -1 (-5425 2075)(-5425 2000);
WIRE 16 -1 (-4725 2025)(-4650 2025);
WIRE 16 -1 (-4725 1900)(-4725 2025);
WIRE 16 -1 (-5100 1550)(-5100 1400);
WIRE 16 -1 (-6825 2175)(-6825 2400);
WIRE 16 -1 (-4650 2925)(-5775 2925);
WIRE 16 -1 (-5775 2925)(-5775 2775);
WIRE 16 -1 (-5475 3425)(-5475 3325);
WIRE 16 -1 (-6975 4000)(-6975 3950);
WIRE 16 -1 (-6600 3950)(-6600 4000);
WIRE 16 -1 (-6225 3950)(-6225 4000);
WIRE 16 -1 (-5850 3950)(-5850 4000);
WIRE 16 -1 (-1700 1225)(-1700 1450);
WIRE 16 682 (-1325 4200)(-1325 4750);
WIRE 16 682 (-2375 4200)(-1325 4200);
WIRE 16 682 (-1325 4750)(-2375 4750);
WIRE 16 682 (-2375 4750)(-2375 4200);
WIRE 16 -1 (-3625 4200)(-3375 4200);
WIRE 16 -1 (-3375 4200)(-3375 3850);
WIRE 16 -1 (-3375 3850)(-3000 3850);
FORCEPROP 2 LAST SIG_NAME VR_PVPP_DEF_PHASE
J 0
(-3360 3860);
DISPLAY 0.617021 (-3360 3860);
PAINT ORANGE (-3360 3860);
FORCEPROP 2 LASTPROP $XRERR UNIQUE?
J 0
(-3600 3860);
DISPLAY 0.638298 (-3600 3860);
PAINT MONO (-3600 3860);
DISPLAY INVISIBLE (-3600 3860);
WIRE 16 -1 (-3375 3475)(-3375 3850);
WIRE 16 -1 (-3375 3425)(-3375 3475);
WIRE 16 -1 (-3650 3475)(-3375 3475);
WIRE 16 -1 (-2750 3850)(-3000 3850);
WIRE 16 -1 (-3000 3800)(-3000 3850);
WIRE 16 -1 (-3375 3375)(-3375 3425);
WIRE 16 -1 (-3650 3425)(-3375 3425);
WIRE 16 -1 (-3375 3325)(-3375 3375);
WIRE 16 -1 (-3650 3375)(-3375 3375);
WIRE 16 -1 (-3375 3275)(-3375 3325);
WIRE 16 -1 (-3650 3325)(-3375 3325);
WIRE 16 -1 (-3375 3225)(-3375 3275);
WIRE 16 -1 (-3650 3275)(-3375 3275);
WIRE 16 -1 (-3375 3175)(-3375 3225);
WIRE 16 -1 (-3650 3225)(-3375 3225);
WIRE 16 -1 (-3375 3125)(-3375 3175);
WIRE 16 -1 (-3650 3175)(-3375 3175);
WIRE 16 -1 (-3650 3125)(-3375 3125);
WIRE 16 -1 (-3375 3025)(-3375 3125);
WIRE 16 -1 (-3650 3025)(-3375 3025);
WIRE 16 2175 (-3525 4375)(-3525 4000);
WIRE 16 2175 (-4750 4375)(-3525 4375);
WIRE 16 2175 (-3525 4000)(-4750 4000);
WIRE 16 2175 (-4750 4000)(-4750 4375);
WIRE 16 2175 (-1775 3125)(-1125 3125);
WIRE 16 2175 (-1775 1325)(-1775 3125);
WIRE 16 2175 (-1125 3125)(-1125 1325);
WIRE 16 2175 (-1775 1325)(-1125 1325);
WIRE 16 -1 (-1375 2725)(-1375 2800);
WIRE 16 -1 (-1375 2800)(-1700 2800);
WIRE 16 -1 (-1700 2800)(-1700 2825);
WIRE 16 -1 (-1700 2275)(-1700 2800);
FORCEPROP 0 LAST SIG_NAME VSENSE_PVPP_DEF
R 1
J 0
(-1710 2310);
DISPLAY 0.617021 (-1710 2310);
PAINT ORANGE (-1710 2310);
FORCEPROP 2 LASTPROP $XRERR UNIQUE?
J 0
(-1950 2310);
DISPLAY 0.638298 (-1950 2310);
PAINT MONO (-1950 2310);
DISPLAY INVISIBLE (-1950 2310);
WIRE 16 -1 (-1375 2175)(-1375 2525);
FORCEPROP 0 LAST SIG_NAME VR_COMP_PVPP_DEF
R 1
J 0
(-1385 2160);
DISPLAY 0.617021 (-1385 2160);
PAINT ORANGE (-1385 2160);
FORCEPROP 2 LASTPROP $XRERR UNIQUE?
J 0
(-1625 2160);
DISPLAY 0.638298 (-1625 2160);
PAINT MONO (-1625 2160);
DISPLAY INVISIBLE (-1625 2160);
WIRE 16 -1 (-1375 1975)(-1375 1825);
WIRE 16 -1 (-1375 1825)(-1700 1825);
WIRE 16 -1 (-1700 2075)(-1700 1825);
WIRE 16 -1 (-1700 1825)(-1700 1725);
WIRE 16 -1 (-1700 1725)(-1700 1650);
WIRE 16 -1 (-2225 1725)(-1700 1725);
FORCEPROP 0 LAST SIG_NAME VR_FB_PVPP_DEF
J 0
(-2185 1735);
DISPLAY 0.617021 (-2185 1735);
PAINT ORANGE (-2185 1735);
FORCEPROP 2 LASTPROP $XRERR UNIQUE?
J 0
(-2425 1735);
DISPLAY 0.638298 (-2425 1735);
PAINT MONO (-2425 1735);
DISPLAY INVISIBLE (-2425 1735);
WIRE 16 -1 (-2225 1725)(-2225 2925);
WIRE 16 -1 (-2225 2925)(-2325 2925);
WIRE 16 -1 (-2325 2825)(-2325 2925);
WIRE 16 -1 (-3650 2925)(-2325 2925);
WIRE 16 -1 (-2325 2450)(-2325 2825);
WIRE 16 -1 (-2675 2825)(-2325 2825);
WIRE 16 -1 (-2325 2450)(-2400 2450);
WIRE 16 -1 (-3000 3450)(-3000 3600);
FORCEPROP 2 LAST SIG_NAME VR_PVPP_DEF_SNUB
J 0
(-2985 3510);
DISPLAY 0.617021 (-2985 3510);
PAINT ORANGE (-2985 3510);
FORCEPROP 2 LASTPROP $XRERR UNIQUE?
J 0
(-3225 3510);
DISPLAY 0.638298 (-3225 3510);
PAINT MONO (-3225 3510);
DISPLAY INVISIBLE (-3225 3510);
WIRE 16 -1 (-3350 2825)(-2875 2825);
WIRE 16 -1 (-3350 2450)(-3350 2825);
FORCEPROP 0 LAST SIG_NAME VR_COMP_PVPP_DEF_3
J 0
(-3485 2835);
DISPLAY 0.617021 (-3485 2835);
PAINT ORANGE (-3485 2835);
FORCEPROP 2 LASTPROP $XRERR UNIQUE?
J 0
(-3725 2835);
DISPLAY 0.638298 (-3725 2835);
PAINT MONO (-3725 2835);
DISPLAY INVISIBLE (-3725 2835);
WIRE 16 -1 (-3650 2825)(-3350 2825);
WIRE 16 -1 (-3300 2450)(-3350 2450);
WIRE 16 -1 (-2600 2450)(-3100 2450);
FORCEPROP 0 LAST SIG_NAME VR_COMP_RC_PVPP_DEF
J 0
(-3085 2460);
DISPLAY 0.617021 (-3085 2460);
PAINT ORANGE (-3085 2460);
FORCEPROP 2 LASTPROP $XRERR UNIQUE?
J 0
(-3325 2460);
DISPLAY 0.638298 (-3325 2460);
PAINT MONO (-3325 2460);
DISPLAY INVISIBLE (-3325 2460);
WIRE 16 -1 (-3600 3900)(-3600 3575);
WIRE 16 -1 (-4650 3900)(-3600 3900);
WIRE 16 -1 (-3600 3575)(-3650 3575);
WIRE 16 -1 (-4650 4200)(-4650 3900);
FORCEPROP 2 LAST SIG_NAME VR_PVPP_DEF_BOOT
J 0
(-4560 3935);
DISPLAY 0.617021 (-4560 3935);
PAINT ORANGE (-4560 3935);
FORCEPROP 2 LASTPROP $XRERR UNIQUE?
J 0
(-4800 3935);
DISPLAY 0.638298 (-4800 3935);
PAINT MONO (-4800 3935);
DISPLAY INVISIBLE (-4800 3935);
WIRE 16 -1 (-4525 4200)(-4650 4200);
WIRE 16 -1 (-2950 975)(-3775 975);
FORCEPROP 2 LAST SIG_NAME PWRGD_PVPP_DEF
J 0
(-3460 985);
DISPLAY 0.617021 (-3460 985);
PAINT ORANGE (-3460 985);
WIRE 16 -1 (-4225 825)(-4225 975);
WIRE 16 -1 (-3975 975)(-4225 975);
FORCEPROP 2 LAST SIG_NAME PWRGD_PVPP_DEF_R
J 0
(-4485 985);
DISPLAY 0.617021 (-4485 985);
PAINT ORANGE (-4485 985);
FORCEPROP 2 LASTPROP $XRERR UNIQUE?
J 0
(-4725 985);
DISPLAY 0.638298 (-4725 985);
PAINT MONO (-4725 985);
DISPLAY INVISIBLE (-4725 985);
WIRE 16 -1 (-4225 975)(-4575 975);
WIRE 16 -1 (-4575 1150)(-4575 975);
WIRE 16 -1 (-4575 975)(-4900 975);
WIRE 16 -1 (-4900 975)(-4900 2525);
WIRE 16 -1 (-4650 2525)(-4900 2525);
WIRE 16 -1 (-3825 4200)(-4325 4200);
FORCEPROP 2 LAST SIG_NAME VR_PVPP_DEF_BOOT_R
J 0
(-4305 4210);
DISPLAY 0.617021 (-4305 4210);
PAINT ORANGE (-4305 4210);
FORCEPROP 2 LASTPROP $XRERR UNIQUE?
J 0
(-4545 4210);
DISPLAY 0.638298 (-4545 4210);
PAINT MONO (-4545 4210);
DISPLAY INVISIBLE (-4545 4210);
WIRE 16 -1 (-7375 4225)(-7375 4300);
WIRE 16 -1 (-6975 4300)(-7375 4300);
WIRE 16 -1 (-7625 4300)(-7375 4300);
WIRE 16 -1 (-6600 4300)(-6975 4300);
WIRE 16 -1 (-6975 4200)(-6975 4300);
WIRE 16 -1 (-6225 4300)(-6600 4300);
FORCEPROP 0 LAST SIG_NAME VR_FET_SW_P12V_STBY_PVPP_DEF
J 0
(-6260 4310);
DISPLAY 0.617021 (-6260 4310);
PAINT ORANGE (-6260 4310);
FORCEPROP 2 LASTPROP $XRERR UNIQUE?
J 0
(-6500 4310);
DISPLAY 0.638298 (-6500 4310);
PAINT MONO (-6500 4310);
DISPLAY INVISIBLE (-6500 4310);
WIRE 16 -1 (-6600 4200)(-6600 4300);
WIRE 16 -1 (-5850 4300)(-6225 4300);
WIRE 16 -1 (-6225 4200)(-6225 4300);
WIRE 16 -1 (-5300 4300)(-5850 4300);
WIRE 16 -1 (-5850 4200)(-5850 4300);
WIRE 16 -1 (-5300 4300)(-5075 4300);
WIRE 16 -1 (-5300 4250)(-5300 4300);
WIRE 16 -1 (-5075 4300)(-5075 3750);
WIRE 16 -1 (-5075 3750)(-5075 3575);
WIRE 16 -1 (-5475 3750)(-5075 3750);
WIRE 16 -1 (-5475 3625)(-5475 3750);
WIRE 16 -1 (-4650 3575)(-5075 3575);
WIRE 16 -1 (-5075 3575)(-5075 3475);
WIRE 16 -1 (-5075 3475)(-4650 3475);
WIRE 16 -1 (-5075 3425)(-5075 3475);
WIRE 16 -1 (-4650 3425)(-5075 3425);
WIRE 16 -1 (-5075 3375)(-5075 3425);
WIRE 16 -1 (-4650 3375)(-5075 3375);
WIRE 16 -1 (-5075 3325)(-5075 3375);
WIRE 16 -1 (-4650 3325)(-5075 3325);
WIRE 16 -1 (-5075 3275)(-5075 3325);
WIRE 16 -1 (-4650 3275)(-5075 3275);
WIRE 16 -1 (-5075 3225)(-5075 3275);
WIRE 16 -1 (-4650 3225)(-5075 3225);
WIRE 16 -1 (-5075 3175)(-5075 3225);
WIRE 16 -1 (-4650 3175)(-5075 3175);
WIRE 16 -1 (-5075 3125)(-5075 3175);
WIRE 16 -1 (-4650 3125)(-5075 3125);
WIRE 16 2175 (-7550 4400)(-5375 4400);
WIRE 16 2175 (-7550 3875)(-7550 4400);
WIRE 16 2175 (-5375 4400)(-5375 3875);
WIRE 16 2175 (-5375 3875)(-7550 3875);
WIRE 16 -1 (-5100 2625)(-4650 2625);
WIRE 16 -1 (-5100 1750)(-5100 2625);
FORCEPROP 2 LAST SIG_NAME VR_PVPP_DEF_ISET
R 1
J 0
(-5110 2110);
DISPLAY 0.617021 (-5110 2110);
PAINT ORANGE (-5110 2110);
FORCEPROP 2 LASTPROP $XRERR UNIQUE?
J 0
(-5350 2110);
DISPLAY 0.638298 (-5350 2110);
PAINT MONO (-5350 2110);
DISPLAY INVISIBLE (-5350 2110);
WIRE 16 -1 (-6125 3025)(-4650 3025);
FORCEPROP 0 LAST SIG_NAME VR_VB_PVPP_DEF
J 0
(-5735 3035);
DISPLAY 0.617021 (-5735 3035);
PAINT ORANGE (-5735 3035);
FORCEPROP 2 LASTPROP $XRERR UNIQUE?
J 0
(-5975 3035);
DISPLAY 0.638298 (-5975 3035);
PAINT MONO (-5975 3035);
DISPLAY INVISIBLE (-5975 3035);
WIRE 16 -1 (-6125 2525)(-6125 3025);
WIRE 16 -1 (-4650 2725)(-5425 2725);
WIRE 16 -1 (-5425 2725)(-5425 2275);
FORCEPROP 2 LAST SIG_NAME VR_PVPP_DEF_SS
R 1
J 0
(-5435 2285);
DISPLAY 0.617021 (-5435 2285);
PAINT ORANGE (-5435 2285);
FORCEPROP 2 LASTPROP $XRERR UNIQUE?
J 0
(-5675 2285);
DISPLAY 0.638298 (-5675 2285);
PAINT MONO (-5675 2285);
DISPLAY INVISIBLE (-5675 2285);
WIRE 16 2175 (-5250 1300)(-5250 500);
WIRE 16 2175 (-8675 1300)(-5250 1300);
WIRE 16 2175 (-5250 500)(-8675 500);
WIRE 16 2175 (-8675 500)(-8675 1300);
WIRE 16 -1 (-4650 2825)(-6400 2825);
FORCEPROP 2 LAST SIG_NAME FM_PVPP_PVDDQ_CPU0_EN_DEF
J 0
(-5501 2850);
DISPLAY 0.617021 (-5501 2850);
PAINT ORANGE (-5501 2850);
FORCEPROP 2 LASTPROP $XRERR UNIQUE?
J 0
(-5741 2850);
DISPLAY 0.638298 (-5741 2850);
PAINT MONO (-5741 2850);
DISPLAY INVISIBLE (-5741 2850);
WIRE 16 -1 (-6600 2825)(-6825 2825);
WIRE 16 -1 (-6825 2600)(-6825 2825);
WIRE 16 -1 (-6825 2825)(-7825 2825);
FORCEPROP 2 LAST SIG_NAME FM_PVPP_CPU0_EN
J 0
(-7801 2850);
DISPLAY 0.617021 (-7801 2850);
PAINT ORANGE (-7801 2850);
DOT 1 (-8300 625);
DOT 1 (-8550 1050);
DOT 1 (-8300 1050);
DOT 1 (-8025 625);
DOT 1 (-7775 625);
DOT 1 (-7500 625);
DOT 1 (-7200 625);
DOT 1 (-8025 1050);
DOT 1 (-7775 1050);
DOT 1 (-7500 1050);
DOT 1 (-7200 1050);
DOT 1 (-6925 625);
DOT 1 (-6625 625);
DOT 1 (-6325 625);
DOT 1 (-6925 1050);
DOT 1 (-6625 1050);
DOT 1 (-6325 1050);
DOT 1 (-6825 2825);
DOT 1 (-6050 625);
DOT 1 (-5775 625);
DOT 1 (-5600 625);
DOT 1 (-6050 1050);
DOT 1 (-5775 1050);
DOT 1 (-4575 975);
DOT 1 (-4225 975);
DOT 1 (-5075 3175);
DOT 1 (-5075 3225);
DOT 1 (-5075 3275);
DOT 1 (-5075 3325);
DOT 1 (-5075 3425);
DOT 1 (-5075 3375);
DOT 1 (-5075 3475);
DOT 1 (-5075 3575);
DOT 1 (-5075 3750);
DOT 1 (-7375 4300);
DOT 1 (-6975 4300);
DOT 1 (-6600 4300);
DOT 1 (-6225 4300);
DOT 1 (-5850 4300);
DOT 1 (-5300 4300);
DOT 1 (-3425 2025);
DOT 1 (-3425 2075);
DOT 1 (-3425 2125);
DOT 1 (-3425 2175);
DOT 1 (-3425 2275);
DOT 1 (-3425 2225);
DOT 1 (-3425 2325);
DOT 1 (-3425 2375);
DOT 1 (-3425 2425);
DOT 1 (-3425 2525);
DOT 1 (-3425 2475);
DOT 1 (-3425 2575);
DOT 1 (-3425 2625);
DOT 1 (-3425 2675);
DOT 1 (-3350 2825);
DOT 1 (-3375 3125);
DOT 1 (-3375 3175);
DOT 1 (-3375 3225);
DOT 1 (-3375 3275);
DOT 1 (-3375 3325);
DOT 1 (-3375 3375);
DOT 1 (-3375 3425);
DOT 1 (-3375 3475);
DOT 1 (-3375 3850);
DOT 1 (-2325 2825);
DOT 1 (-2325 2925);
DOT 1 (-3000 3850);
DOT 1 (-2075 3450);
DOT 1 (-2425 3850);
DOT 1 (-2075 3850);
DOT 1 (-1700 1725);
DOT 1 (-1700 1825);
DOT 1 (-1700 2800);
DOT 1 (-1800 3850);
DOT 1 (-1475 3850);
DOT 1 (-1200 3850);
DOT 1 (-1150 3850);
FORCENOTE
CAPS TO BE PLACED BETWEEN DIMMS
(-8195 1205) 0;
DISPLAY LEFT (-8195 1205);
DISPLAY 1.021277 (-8195 1205);
PAINT PURPLE (-8195 1205);
FORCENOTE
BOM_COST: PVPP_DEF_VR
(-7761 159) 0;
DISPLAY LEFT (-7761 159);
DISPLAY 1.021277 (-7761 159);
PAINT PURPLE (-7761 159);
FORCENOTE
ROOM = PVPP_DEF_VR
(-7770 257) 0;
DISPLAY LEFT (-7770 257);
DISPLAY 1.021277 (-7770 257);
PAINT PURPLE (-7770 257);
FORCENOTE
25A OC
(-5545 1630) 0;
DISPLAY LEFT (-5545 1630);
PAINT PURPLE (-5545 1630);
FORCENOTE
6.25MS
(-5770 2180) 0;
DISPLAY LEFT (-5770 2180);
PAINT PURPLE (-5770 2180);
FORCENOTE
(0.4V/MS)
(-5795 2130) 0;
DISPLAY LEFT (-5795 2130);
PAINT PURPLE (-5795 2130);
FORCENOTE
SPOF
(-4750 4425) 0;
DISPLAY LEFT (-4750 4425);
DISPLAY 1.659574 (-4750 4425);
PAINT PURPLE (-4750 4425);
FORCENOTE
PLACE ON
(-4450 4425) 0;
DISPLAY LEFT (-4450 4425);
DISPLAY 1.042553 (-4450 4425);
PAINT PURPLE (-4450 4425);
FORCENOTE
COMPENSATION TYPE III
(-3325 2150) 0;
DISPLAY LEFT (-3325 2150);
DISPLAY 1.042553 (-3325 2150);
PAINT PURPLE (-3325 2150);
FORCENOTE
SPOF
(-1555 2975) 0;
DISPLAY LEFT (-1555 2975);
DISPLAY 2.340426 (-1555 2975);
PAINT PURPLE (-1555 2975);
FORCENOTE
TOP LAYER
(-4075 4425) 0;
DISPLAY LEFT (-4075 4425);
DISPLAY 1.042553 (-4075 4425);
PAINT PURPLE (-4075 4425);
FORCENOTE
VOUT = 2.5V
(-2350 4675) 0;
DISPLAY LEFT (-2350 4675);
DISPLAY 1.021277 (-2350 4675);
PAINT PURPLE (-2350 4675);
FORCENOTE
DC TOL = +/-1.5%
(-2350 4575) 0;
DISPLAY LEFT (-2350 4575);
DISPLAY 1.021277 (-2350 4575);
PAINT PURPLE (-2350 4575);
FORCENOTE
IOUT TDC = 8A
(-2350 4475) 0;
DISPLAY LEFT (-2350 4475);
DISPLAY 1.021277 (-2350 4475);
PAINT PURPLE (-2350 4475);
FORCENOTE
IOUT PK = 15A
(-2350 4425) 0;
DISPLAY LEFT (-2350 4425);
DISPLAY 1.021277 (-2350 4425);
PAINT PURPLE (-2350 4425);
FORCENOTE
RIPPLE GUIDELINE = +/- 1.0%
(-2350 4625) 0;
DISPLAY LEFT (-2350 4625);
DISPLAY 1.021277 (-2350 4625);
PAINT PURPLE (-2350 4625);
FORCENOTE
AC & RIPPLE TOL = +3.5%, -7.3%
(-2350 4525) 0;
DISPLAY LEFT (-2350 4525);
DISPLAY 1.021277 (-2350 4525);
PAINT PURPLE (-2350 4525);
FORCENOTE
IOUT STEP = 3A
(-2350 4375) 0;
DISPLAY LEFT (-2350 4375);
DISPLAY 1.021277 (-2350 4375);
PAINT PURPLE (-2350 4375);
FORCENOTE
SW FREQ =  500KHZ
(-2350 4275) 0;
DISPLAY LEFT (-2350 4275);
DISPLAY 1.021277 (-2350 4275);
PAINT PURPLE (-2350 4275);
FORCENOTE
IOUT DI/DT = 25A/US
(-2350 4325) 0;
DISPLAY LEFT (-2350 4325);
DISPLAY 1.021277 (-2350 4325);
PAINT PURPLE (-2350 4325);
QUIT
